G04 ================== begin FILE IDENTIFICATION RECORD ==================*
G04 Layout Name:  15105-sa.brd*
G04 Film Name:    SE_REF_L8*
G04 File Format:  Gerber RS274X*
G04 File Origin:  Cadence Allegro 16.5-S056*
G04 Origin Date:  Wed Nov 16 02:02:49 2016*
G04 *
G04 Layer:  BOARD GEOMETRY/SE_REF_L8_TBL*
G04 Layer:  BOARD GEOMETRY/SE_REF_L8_BOTTOM*
G04 Layer:  BOARD GEOMETRY/PANEL_OUTLINE*
G04 *
G04 Offset:    (0.00 0.00)*
G04 Mirror:    No*
G04 Mode:      Positive*
G04 Rotation:  0*
G04 FullContactRelief:  No*
G04 UndefLineWidth:     6.00*
G04 ================== end FILE IDENTIFICATION RECORD ====================*
%FSLAX35Y35*MOIN*%
%IR0*IPPOS*OFA0.00000B0.00000*MIA0B0*SFA1.00000B1.00000*%
%ADD10C,.02*%
%ADD11C,.006*%
%ADD12C,.00475*%
G75*
%LPD*%
G75*
G54D10*
G01X1479970Y793988D02*
X2197470D01*
G01X1479970Y863288D02*
Y793988D01*
G01Y828638D02*
X2197470D01*
G01X1479970Y863288D02*
X2197470D01*
G01X1654970D02*
Y793988D01*
G01X1882470Y863288D02*
Y793988D01*
G01X1987470Y863288D02*
Y793988D01*
G01X2197470Y863288D02*
Y793988D01*
G54D11*
G01X-27072Y-83981D02*
Y-101481D01*
G01X-32094Y-83981D02*
X-22050D01*
G01X-13284Y-101481D02*
Y-83981D01*
G01Y-92439D02*
X-12192Y-90981D01*
X-11100Y-90106D01*
X-9354Y-89815D01*
X-8044Y-90106D01*
X-6515Y-91273D01*
X-5860Y-93023D01*
Y-101481D01*
G01X7928Y-89815D02*
Y-101481D01*
G01Y-85148D02*
X7491Y-84856D01*
Y-84273D01*
X7928Y-83981D01*
X8365Y-84273D01*
Y-84856D01*
X7928Y-85148D01*
G01X22153Y-99440D02*
X23245Y-100606D01*
X24773Y-101481D01*
X26083D01*
X27393Y-100898D01*
X28266Y-100023D01*
X28703Y-98857D01*
X28485Y-97106D01*
X27611Y-96231D01*
X23681Y-94481D01*
X22808Y-92439D01*
X23245Y-90981D01*
X24118Y-90106D01*
X25428Y-89815D01*
X26738Y-90106D01*
X28048Y-90981D01*
G01X57371Y-105856D02*
X58900Y-107023D01*
X60646Y-107314D01*
X62174Y-107023D01*
X63485Y-105565D01*
X64358Y-103523D01*
Y-89815D01*
G01Y-92148D02*
X63485Y-90981D01*
X62174Y-90106D01*
X60646Y-89815D01*
X58900Y-90398D01*
X57808Y-91564D01*
X56934Y-93606D01*
X56498Y-95648D01*
X56716Y-97398D01*
X57590Y-99440D01*
X58900Y-100898D01*
X60646Y-101481D01*
X61956Y-101189D01*
X63485Y-100023D01*
X64358Y-98857D01*
G01X74653Y-93606D02*
X81640D01*
X80985Y-91564D01*
X79893Y-90398D01*
X78365Y-89815D01*
X76836Y-90106D01*
X75526Y-90981D01*
X74653Y-93023D01*
X74216Y-94773D01*
Y-96523D01*
X74653Y-98273D01*
X75745Y-100023D01*
X77055Y-101189D01*
X78583Y-101481D01*
X80111Y-100898D01*
X81640Y-99148D01*
G01X92371Y-101481D02*
Y-89815D01*
G01Y-92148D02*
X93463Y-90981D01*
X94555Y-90106D01*
X96083Y-89815D01*
X97174Y-90106D01*
X98485Y-90981D01*
G01X108998Y-101481D02*
Y-83981D01*
G01Y-92731D02*
X110090Y-90981D01*
X111400Y-90106D01*
X112710Y-89815D01*
X114674Y-90398D01*
X115985Y-91564D01*
X116858Y-93606D01*
Y-95939D01*
X116421Y-98273D01*
X115548Y-100023D01*
X114020Y-101189D01*
X112710Y-101481D01*
X111400Y-101189D01*
X110090Y-100315D01*
X108998Y-98857D01*
G01X127153Y-93606D02*
X134140D01*
X133485Y-91564D01*
X132393Y-90398D01*
X130865Y-89815D01*
X129336Y-90106D01*
X128026Y-90981D01*
X127153Y-93023D01*
X126716Y-94773D01*
Y-96523D01*
X127153Y-98273D01*
X128245Y-100023D01*
X129555Y-101189D01*
X131083Y-101481D01*
X132611Y-100898D01*
X134140Y-99148D01*
G01X144871Y-101481D02*
Y-89815D01*
G01Y-92148D02*
X145963Y-90981D01*
X147055Y-90106D01*
X148583Y-89815D01*
X149674Y-90106D01*
X150985Y-90981D01*
G01X182928Y-89815D02*
Y-101481D01*
G01Y-85148D02*
X182491Y-84856D01*
Y-84273D01*
X182928Y-83981D01*
X183365Y-84273D01*
Y-84856D01*
X182928Y-85148D01*
G01X197153Y-99440D02*
X198245Y-100606D01*
X199773Y-101481D01*
X201083D01*
X202393Y-100898D01*
X203266Y-100023D01*
X203703Y-98857D01*
X203485Y-97106D01*
X202611Y-96231D01*
X198681Y-94481D01*
X197808Y-92439D01*
X198245Y-90981D01*
X199118Y-90106D01*
X200428Y-89815D01*
X201738Y-90106D01*
X203048Y-90981D01*
G01X231934Y-105856D02*
X233463Y-107023D01*
X234773Y-107314D01*
X236520Y-106731D01*
X237830Y-105273D01*
X238485Y-102647D01*
Y-89815D01*
G01Y-85148D02*
X238048Y-84856D01*
Y-84273D01*
X238485Y-83981D01*
X238921Y-84273D01*
Y-84856D01*
X238485Y-85148D01*
G01X249216Y-89815D02*
Y-97981D01*
X250090Y-100023D01*
X251400Y-101189D01*
X252928Y-101481D01*
X254456Y-101189D01*
X255766Y-100023D01*
X256640Y-97981D01*
G01Y-101481D02*
Y-89815D01*
G01X267153Y-99440D02*
X268245Y-100606D01*
X269773Y-101481D01*
X271083D01*
X272393Y-100898D01*
X273266Y-100023D01*
X273703Y-98857D01*
X273485Y-97106D01*
X272611Y-96231D01*
X268681Y-94481D01*
X267808Y-92439D01*
X268245Y-90981D01*
X269118Y-90106D01*
X270428Y-89815D01*
X271738Y-90106D01*
X273048Y-90981D01*
G01X287928Y-83981D02*
Y-101481D01*
G01X284871Y-89815D02*
X290985D01*
G01X321618Y-101481D02*
Y-86606D01*
X322055Y-85148D01*
X322928Y-84273D01*
X324238Y-83981D01*
X325548Y-84564D01*
X326203Y-86023D01*
G01X323583Y-90981D02*
X319216D01*
G01X340428Y-101481D02*
X339118Y-101189D01*
X337808Y-100023D01*
X336934Y-97981D01*
X336498Y-95648D01*
X336934Y-93314D01*
X337808Y-91273D01*
X339118Y-90106D01*
X340428Y-89815D01*
X341738Y-90106D01*
X343048Y-91273D01*
X343921Y-93314D01*
X344140Y-95648D01*
X343921Y-97981D01*
X343048Y-100023D01*
X341738Y-101189D01*
X340428Y-101481D01*
G01X354871D02*
Y-89815D01*
G01Y-92148D02*
X355963Y-90981D01*
X357055Y-90106D01*
X358583Y-89815D01*
X359674Y-90106D01*
X360985Y-90981D01*
G01X388343Y-106731D02*
X389653Y-107314D01*
X391400Y-106731D01*
X392491Y-105565D01*
X393365Y-104106D01*
X394674Y-99440D01*
X397513Y-89815D01*
G01X390526D02*
X394674Y-99440D01*
G01X410428Y-101481D02*
X409118Y-101189D01*
X407808Y-100023D01*
X406934Y-97981D01*
X406498Y-95648D01*
X406934Y-93314D01*
X407808Y-91273D01*
X409118Y-90106D01*
X410428Y-89815D01*
X411738Y-90106D01*
X413048Y-91273D01*
X413921Y-93314D01*
X414140Y-95648D01*
X413921Y-97981D01*
X413048Y-100023D01*
X411738Y-101189D01*
X410428Y-101481D01*
G01X424216Y-89815D02*
Y-97981D01*
X425090Y-100023D01*
X426400Y-101189D01*
X427928Y-101481D01*
X429456Y-101189D01*
X430766Y-100023D01*
X431640Y-97981D01*
G01Y-101481D02*
Y-89815D01*
G01X442371Y-101481D02*
Y-89815D01*
G01Y-92148D02*
X443463Y-90981D01*
X444555Y-90106D01*
X446083Y-89815D01*
X447174Y-90106D01*
X448485Y-90981D01*
G01X477371Y-101481D02*
Y-89815D01*
G01Y-92148D02*
X478463Y-90981D01*
X479555Y-90106D01*
X481083Y-89815D01*
X482174Y-90106D01*
X483485Y-90981D01*
G01X494653Y-93606D02*
X501640D01*
X500985Y-91564D01*
X499893Y-90398D01*
X498365Y-89815D01*
X496836Y-90106D01*
X495526Y-90981D01*
X494653Y-93023D01*
X494216Y-94773D01*
Y-96523D01*
X494653Y-98273D01*
X495745Y-100023D01*
X497055Y-101189D01*
X498583Y-101481D01*
X500111Y-100898D01*
X501640Y-99148D01*
G01X514118Y-101481D02*
Y-86606D01*
X514555Y-85148D01*
X515428Y-84273D01*
X516738Y-83981D01*
X518048Y-84564D01*
X518703Y-86023D01*
G01X516083Y-90981D02*
X511716D01*
G01X529653Y-93606D02*
X536640D01*
X535985Y-91564D01*
X534893Y-90398D01*
X533365Y-89815D01*
X531836Y-90106D01*
X530526Y-90981D01*
X529653Y-93023D01*
X529216Y-94773D01*
Y-96523D01*
X529653Y-98273D01*
X530745Y-100023D01*
X532055Y-101189D01*
X533583Y-101481D01*
X535111Y-100898D01*
X536640Y-99148D01*
G01X547371Y-101481D02*
Y-89815D01*
G01Y-92148D02*
X548463Y-90981D01*
X549555Y-90106D01*
X551083Y-89815D01*
X552174Y-90106D01*
X553485Y-90981D01*
G01X564653Y-93606D02*
X571640D01*
X570985Y-91564D01*
X569893Y-90398D01*
X568365Y-89815D01*
X566836Y-90106D01*
X565526Y-90981D01*
X564653Y-93023D01*
X564216Y-94773D01*
Y-96523D01*
X564653Y-98273D01*
X565745Y-100023D01*
X567055Y-101189D01*
X568583Y-101481D01*
X570111Y-100898D01*
X571640Y-99148D01*
G01X581716Y-101481D02*
Y-89815D01*
G01Y-92731D02*
X582590Y-91273D01*
X583900Y-90106D01*
X585646Y-89815D01*
X587174Y-90106D01*
X588485Y-91273D01*
X589140Y-93314D01*
Y-101481D01*
G01X606421Y-91273D02*
X604893Y-90106D01*
X603583Y-89815D01*
X601836Y-90398D01*
X600526Y-91564D01*
X599653Y-93606D01*
X599434Y-95648D01*
X599653Y-97690D01*
X600526Y-99440D01*
X601836Y-100898D01*
X603583Y-101481D01*
X605111Y-100898D01*
X606421Y-99731D01*
G01X617153Y-93606D02*
X624140D01*
X623485Y-91564D01*
X622393Y-90398D01*
X620865Y-89815D01*
X619336Y-90106D01*
X618026Y-90981D01*
X617153Y-93023D01*
X616716Y-94773D01*
Y-96523D01*
X617153Y-98273D01*
X618245Y-100023D01*
X619555Y-101189D01*
X621083Y-101481D01*
X622611Y-100898D01*
X624140Y-99148D01*
G01X655428Y-83981D02*
Y-101481D01*
G01X652371Y-89815D02*
X658485D01*
G01X672928Y-101481D02*
X671618Y-101189D01*
X670308Y-100023D01*
X669434Y-97981D01*
X668998Y-95648D01*
X669434Y-93314D01*
X670308Y-91273D01*
X671618Y-90106D01*
X672928Y-89815D01*
X674238Y-90106D01*
X675548Y-91273D01*
X676421Y-93314D01*
X676640Y-95648D01*
X676421Y-97981D01*
X675548Y-100023D01*
X674238Y-101189D01*
X672928Y-101481D01*
G01X706618D02*
Y-86606D01*
X707055Y-85148D01*
X707928Y-84273D01*
X709238Y-83981D01*
X710548Y-84564D01*
X711203Y-86023D01*
G01X708583Y-90981D02*
X704216D01*
G01X725428Y-89815D02*
Y-101481D01*
G01Y-85148D02*
X724991Y-84856D01*
Y-84273D01*
X725428Y-83981D01*
X725865Y-84273D01*
Y-84856D01*
X725428Y-85148D01*
G01X739216Y-101481D02*
Y-89815D01*
G01Y-92731D02*
X740090Y-91273D01*
X741400Y-90106D01*
X743146Y-89815D01*
X744674Y-90106D01*
X745985Y-91273D01*
X746640Y-93314D01*
Y-101481D01*
G01X764358Y-83981D02*
Y-101481D01*
G01Y-98857D02*
X763485Y-100315D01*
X762174Y-101189D01*
X760646Y-101481D01*
X758900Y-100898D01*
X757590Y-99440D01*
X756716Y-97690D01*
X756498Y-95648D01*
X756716Y-93606D01*
X757590Y-91856D01*
X758900Y-90398D01*
X760646Y-89815D01*
X762174Y-90106D01*
X763266Y-90690D01*
X764358Y-91856D01*
G01X795428Y-83981D02*
Y-101481D01*
G01X792371Y-89815D02*
X798485D01*
G01X809216Y-101481D02*
Y-83981D01*
G01Y-92439D02*
X810308Y-90981D01*
X811400Y-90106D01*
X813146Y-89815D01*
X814456Y-90106D01*
X815985Y-91273D01*
X816640Y-93023D01*
Y-101481D01*
G01X827153Y-93606D02*
X834140D01*
X833485Y-91564D01*
X832393Y-90398D01*
X830865Y-89815D01*
X829336Y-90106D01*
X828026Y-90981D01*
X827153Y-93023D01*
X826716Y-94773D01*
Y-96523D01*
X827153Y-98273D01*
X828245Y-100023D01*
X829555Y-101189D01*
X831083Y-101481D01*
X832611Y-100898D01*
X834140Y-99148D01*
G01X860843D02*
X862590Y-100606D01*
X864555Y-101481D01*
X866301D01*
X868048Y-100606D01*
X869358Y-99148D01*
X870013Y-97106D01*
X869576Y-95065D01*
X868485Y-93314D01*
X866520Y-92148D01*
X863900Y-91564D01*
X862371Y-90398D01*
X861716Y-88356D01*
X862153Y-86314D01*
X863245Y-84856D01*
X864773Y-83981D01*
X866301D01*
X867830Y-84564D01*
X869140Y-86023D01*
G01X887295Y-101481D02*
X878561D01*
Y-83981D01*
X887295D01*
G01X883801Y-92439D02*
X878561D01*
G01X917928Y-89815D02*
Y-101481D01*
G01Y-85148D02*
X917491Y-84856D01*
Y-84273D01*
X917928Y-83981D01*
X918365Y-84273D01*
Y-84856D01*
X917928Y-85148D01*
G01X928878Y-101481D02*
Y-89815D01*
G01Y-93023D02*
X929533Y-91564D01*
X930625Y-90398D01*
X932153Y-89815D01*
X933681Y-90398D01*
X934773Y-91564D01*
X935428Y-93023D01*
Y-101481D01*
G01Y-93023D02*
X936083Y-91564D01*
X937174Y-90398D01*
X938703Y-89815D01*
X940231Y-90398D01*
X941323Y-91564D01*
X941978Y-93314D01*
Y-101481D01*
G01X948998Y-107314D02*
Y-89815D01*
G01Y-92439D02*
X950090Y-90981D01*
X951181Y-90106D01*
X952928Y-89815D01*
X954456Y-90106D01*
X955985Y-91564D01*
X956640Y-93606D01*
X956858Y-95648D01*
X956640Y-97690D01*
X955985Y-99731D01*
X954674Y-100898D01*
X952928Y-101481D01*
X951400Y-101189D01*
X949871Y-100315D01*
X948998Y-99148D01*
G01X967153Y-93606D02*
X974140D01*
X973485Y-91564D01*
X972393Y-90398D01*
X970865Y-89815D01*
X969336Y-90106D01*
X968026Y-90981D01*
X967153Y-93023D01*
X966716Y-94773D01*
Y-96523D01*
X967153Y-98273D01*
X968245Y-100023D01*
X969555Y-101189D01*
X971083Y-101481D01*
X972611Y-100898D01*
X974140Y-99148D01*
G01X991858Y-83981D02*
Y-101481D01*
G01Y-98857D02*
X990985Y-100315D01*
X989674Y-101189D01*
X988146Y-101481D01*
X986400Y-100898D01*
X985090Y-99440D01*
X984216Y-97690D01*
X983998Y-95648D01*
X984216Y-93606D01*
X985090Y-91856D01*
X986400Y-90398D01*
X988146Y-89815D01*
X989674Y-90106D01*
X990766Y-90690D01*
X991858Y-91856D01*
G01X1009358Y-101481D02*
Y-89815D01*
G01Y-91856D02*
X1008485Y-90690D01*
X1007174Y-90106D01*
X1005646Y-89815D01*
X1004118Y-90398D01*
X1002808Y-91564D01*
X1001934Y-93314D01*
X1001498Y-95648D01*
X1001934Y-97981D01*
X1002808Y-99731D01*
X1004118Y-100898D01*
X1005646Y-101481D01*
X1007174Y-101189D01*
X1008485Y-100315D01*
X1009358Y-99148D01*
G01X1019216Y-101481D02*
Y-89815D01*
G01Y-92731D02*
X1020090Y-91273D01*
X1021400Y-90106D01*
X1023146Y-89815D01*
X1024674Y-90106D01*
X1025985Y-91273D01*
X1026640Y-93314D01*
Y-101481D01*
G01X1043921Y-91273D02*
X1042393Y-90106D01*
X1041083Y-89815D01*
X1039336Y-90398D01*
X1038026Y-91564D01*
X1037153Y-93606D01*
X1036934Y-95648D01*
X1037153Y-97690D01*
X1038026Y-99440D01*
X1039336Y-100898D01*
X1041083Y-101481D01*
X1042611Y-100898D01*
X1043921Y-99731D01*
G01X1054653Y-93606D02*
X1061640D01*
X1060985Y-91564D01*
X1059893Y-90398D01*
X1058365Y-89815D01*
X1056836Y-90106D01*
X1055526Y-90981D01*
X1054653Y-93023D01*
X1054216Y-94773D01*
Y-96523D01*
X1054653Y-98273D01*
X1055745Y-100023D01*
X1057055Y-101189D01*
X1058583Y-101481D01*
X1060111Y-100898D01*
X1061640Y-99148D01*
G01X1092928Y-83981D02*
Y-101481D01*
G01X1089871Y-89815D02*
X1095985D01*
G01X1107371Y-101481D02*
Y-89815D01*
G01Y-92148D02*
X1108463Y-90981D01*
X1109555Y-90106D01*
X1111083Y-89815D01*
X1112174Y-90106D01*
X1113485Y-90981D01*
G01X1131858Y-101481D02*
Y-89815D01*
G01Y-91856D02*
X1130985Y-90690D01*
X1129674Y-90106D01*
X1128146Y-89815D01*
X1126618Y-90398D01*
X1125308Y-91564D01*
X1124434Y-93314D01*
X1123998Y-95648D01*
X1124434Y-97981D01*
X1125308Y-99731D01*
X1126618Y-100898D01*
X1128146Y-101481D01*
X1129674Y-101189D01*
X1130985Y-100315D01*
X1131858Y-99148D01*
G01X1148921Y-91273D02*
X1147393Y-90106D01*
X1146083Y-89815D01*
X1144336Y-90398D01*
X1143026Y-91564D01*
X1142153Y-93606D01*
X1141934Y-95648D01*
X1142153Y-97690D01*
X1143026Y-99440D01*
X1144336Y-100898D01*
X1146083Y-101481D01*
X1147611Y-100898D01*
X1148921Y-99731D01*
G01X1159653Y-93606D02*
X1166640D01*
X1165985Y-91564D01*
X1164893Y-90398D01*
X1163365Y-89815D01*
X1161836Y-90106D01*
X1160526Y-90981D01*
X1159653Y-93023D01*
X1159216Y-94773D01*
Y-96523D01*
X1159653Y-98273D01*
X1160745Y-100023D01*
X1162055Y-101189D01*
X1163583Y-101481D01*
X1165111Y-100898D01*
X1166640Y-99148D01*
G01X1177153Y-99440D02*
X1178245Y-100606D01*
X1179773Y-101481D01*
X1181083D01*
X1182393Y-100898D01*
X1183266Y-100023D01*
X1183703Y-98857D01*
X1183485Y-97106D01*
X1182611Y-96231D01*
X1178681Y-94481D01*
X1177808Y-92439D01*
X1178245Y-90981D01*
X1179118Y-90106D01*
X1180428Y-89815D01*
X1181738Y-90106D01*
X1183048Y-90981D01*
G01X1215428Y-89815D02*
Y-101481D01*
G01Y-85148D02*
X1214991Y-84856D01*
Y-84273D01*
X1215428Y-83981D01*
X1215865Y-84273D01*
Y-84856D01*
X1215428Y-85148D01*
G01X1229216Y-101481D02*
Y-89815D01*
G01Y-92731D02*
X1230090Y-91273D01*
X1231400Y-90106D01*
X1233146Y-89815D01*
X1234674Y-90106D01*
X1235985Y-91273D01*
X1236640Y-93314D01*
Y-101481D01*
G01X1267928D02*
Y-83981D01*
G01X1289358Y-101481D02*
Y-89815D01*
G01Y-91856D02*
X1288485Y-90690D01*
X1287174Y-90106D01*
X1285646Y-89815D01*
X1284118Y-90398D01*
X1282808Y-91564D01*
X1281934Y-93314D01*
X1281498Y-95648D01*
X1281934Y-97981D01*
X1282808Y-99731D01*
X1284118Y-100898D01*
X1285646Y-101481D01*
X1287174Y-101189D01*
X1288485Y-100315D01*
X1289358Y-99148D01*
G01X1298343Y-106731D02*
X1299653Y-107314D01*
X1301400Y-106731D01*
X1302491Y-105565D01*
X1303365Y-104106D01*
X1304674Y-99440D01*
X1307513Y-89815D01*
G01X1300526D02*
X1304674Y-99440D01*
G01X1317153Y-93606D02*
X1324140D01*
X1323485Y-91564D01*
X1322393Y-90398D01*
X1320865Y-89815D01*
X1319336Y-90106D01*
X1318026Y-90981D01*
X1317153Y-93023D01*
X1316716Y-94773D01*
Y-96523D01*
X1317153Y-98273D01*
X1318245Y-100023D01*
X1319555Y-101189D01*
X1321083Y-101481D01*
X1322611Y-100898D01*
X1324140Y-99148D01*
G01X1334871Y-101481D02*
Y-89815D01*
G01Y-92148D02*
X1335963Y-90981D01*
X1337055Y-90106D01*
X1338583Y-89815D01*
X1339674Y-90106D01*
X1340985Y-90981D01*
G01X1368561Y-83981D02*
Y-101481D01*
X1377295D01*
G01X1390428D02*
X1391956Y-101189D01*
X1393703Y-100315D01*
X1394795Y-98857D01*
X1395231Y-96814D01*
X1394795Y-94773D01*
X1393485Y-93023D01*
X1391520Y-92148D01*
X1389336D01*
X1388026Y-91564D01*
X1386934Y-90106D01*
X1386498Y-88065D01*
X1387153Y-86023D01*
X1388681Y-84564D01*
X1390428Y-83981D01*
X1392174Y-84564D01*
X1393703Y-86023D01*
X1394358Y-88065D01*
X1393921Y-90106D01*
X1392830Y-91564D01*
X1391520Y-92148D01*
X1389336D01*
X1387371Y-93023D01*
X1386061Y-94773D01*
X1385625Y-96814D01*
X1386061Y-98857D01*
X1387153Y-100315D01*
X1388900Y-101189D01*
X1390428Y-101481D01*
G01X1407928Y-102064D02*
X1407491Y-101773D01*
Y-101189D01*
X1407928Y-100898D01*
X1408365Y-101189D01*
Y-101773D01*
X1407928Y-102064D01*
G01X1481935Y875371D02*
X1483682Y873913D01*
X1485647Y873038D01*
X1487393D01*
X1489140Y873913D01*
X1490450Y875371D01*
X1491105Y877413D01*
X1490668Y879454D01*
X1489577Y881205D01*
X1487612Y882371D01*
X1484992Y882955D01*
X1483463Y884121D01*
X1482808Y886163D01*
X1483245Y888205D01*
X1484337Y889663D01*
X1485865Y890538D01*
X1487393D01*
X1488922Y889955D01*
X1490232Y888496D01*
G01X1508387Y873038D02*
X1499653D01*
Y890538D01*
X1508387D01*
G01X1504893Y882080D02*
X1499653D01*
G01X1536400Y890538D02*
X1541640D01*
G01X1539020D02*
Y873038D01*
G01X1536400D02*
X1541640D01*
G01X1550843D02*
Y890538D01*
X1556520Y875955D01*
X1562197Y890538D01*
Y873038D01*
G01X1569653D02*
Y890538D01*
X1574893D01*
X1576640Y889663D01*
X1577950Y887621D01*
X1578387Y885288D01*
X1577950Y882955D01*
X1576858Y881205D01*
X1574893Y880329D01*
X1569653D01*
G01X1595887Y873038D02*
X1587153D01*
Y890538D01*
X1595887D01*
G01X1592393Y882080D02*
X1587153D01*
G01X1604217Y873038D02*
Y890538D01*
X1608583D01*
X1610330Y889663D01*
X1611640Y888496D01*
X1612732Y886747D01*
X1613605Y884704D01*
X1613823Y881788D01*
X1613605Y878871D01*
X1612732Y876829D01*
X1611640Y875079D01*
X1610330Y873913D01*
X1608583Y873038D01*
X1604217D01*
G01X1621061D02*
X1626520Y890538D01*
X1631979Y873038D01*
G01X1630013Y879163D02*
X1623026D01*
G01X1638998Y873038D02*
Y890538D01*
X1649042Y873038D01*
Y890538D01*
G01X1666323Y889079D02*
X1665013Y889955D01*
X1663485Y890538D01*
X1661738D01*
X1659773Y889663D01*
X1658245Y888205D01*
X1657153Y886454D01*
X1656280Y883538D01*
X1656061Y880913D01*
X1656498Y878288D01*
X1657153Y876538D01*
X1658463Y874788D01*
X1659992Y873621D01*
X1661520Y873038D01*
X1663048D01*
X1664577Y873621D01*
X1665887Y874496D01*
X1666979Y875662D01*
G01X1683387Y873038D02*
X1674653D01*
Y890538D01*
X1683387D01*
G01X1679893Y882080D02*
X1674653D01*
G01X1714020Y890538D02*
Y873038D01*
G01X1708998Y890538D02*
X1719042D01*
G01X1726061Y873038D02*
X1731520Y890538D01*
X1736979Y873038D01*
G01X1735013Y879163D02*
X1728026D01*
G01X1750766Y882371D02*
X1751640Y883246D01*
X1752295Y884704D01*
X1752732Y886747D01*
X1752295Y888496D01*
X1751422Y889663D01*
X1749893Y890538D01*
X1743998D01*
Y873038D01*
X1751203D01*
X1752732Y874204D01*
X1753605Y875955D01*
X1754042Y877996D01*
X1753605Y880038D01*
X1752295Y881788D01*
X1750766Y882371D01*
X1743998D01*
G01X1762153Y890538D02*
Y873038D01*
X1770887D01*
G01X1788387D02*
X1779653D01*
Y890538D01*
X1788387D01*
G01X1784893Y882080D02*
X1779653D01*
G01X1801520Y872455D02*
X1801083Y872746D01*
Y873330D01*
X1801520Y873621D01*
X1801957Y873330D01*
Y872746D01*
X1801520Y872455D01*
G01Y880329D02*
X1801083Y880621D01*
Y881205D01*
X1801520Y881496D01*
X1801957Y881205D01*
Y880621D01*
X1801520Y880329D01*
G01X1832153Y890538D02*
Y873038D01*
X1840887D01*
G01X1854020D02*
X1855548Y873330D01*
X1857295Y874204D01*
X1858387Y875662D01*
X1858823Y877705D01*
X1858387Y879746D01*
X1857077Y881496D01*
X1855112Y882371D01*
X1852928D01*
X1851618Y882955D01*
X1850526Y884413D01*
X1850090Y886454D01*
X1850745Y888496D01*
X1852273Y889955D01*
X1854020Y890538D01*
X1855766Y889955D01*
X1857295Y888496D01*
X1857950Y886454D01*
X1857513Y884413D01*
X1856422Y882955D01*
X1855112Y882371D01*
X1852928D01*
X1850963Y881496D01*
X1849653Y879746D01*
X1849217Y877705D01*
X1849653Y875662D01*
X1850745Y874204D01*
X1852492Y873330D01*
X1854020Y873038D01*
G01X1503600Y855888D02*
X1508840D01*
G01X1506220D02*
Y838388D01*
G01X1503600D02*
X1508840D01*
G01X1518043D02*
Y855888D01*
X1523720Y841305D01*
X1529397Y855888D01*
Y838388D01*
G01X1536853D02*
Y855888D01*
X1542093D01*
X1543840Y855013D01*
X1545150Y852971D01*
X1545587Y850638D01*
X1545150Y848305D01*
X1544058Y846555D01*
X1542093Y845679D01*
X1536853D01*
G01X1557628Y832555D02*
X1555445Y835471D01*
X1554353Y838388D01*
Y850054D01*
X1555445Y852971D01*
X1557628Y855888D01*
G01X1576220Y838388D02*
X1574473Y838680D01*
X1572945Y839846D01*
X1571635Y841596D01*
X1570761Y843638D01*
X1570325Y845971D01*
Y848305D01*
X1570761Y850638D01*
X1571635Y852680D01*
X1572945Y854429D01*
X1574473Y855596D01*
X1576220Y855888D01*
X1577966Y855596D01*
X1579495Y854429D01*
X1580805Y852680D01*
X1581679Y850638D01*
X1582115Y848305D01*
Y845971D01*
X1581679Y843638D01*
X1580805Y841596D01*
X1579495Y839846D01*
X1577966Y838680D01*
X1576220Y838388D01*
G01X1590008D02*
Y855888D01*
G01Y847430D02*
X1591100Y848888D01*
X1592192Y849763D01*
X1593938Y850054D01*
X1595248Y849763D01*
X1596777Y848596D01*
X1597432Y846846D01*
Y838388D01*
G01X1604670D02*
Y850054D01*
G01Y846846D02*
X1605325Y848305D01*
X1606417Y849471D01*
X1607945Y850054D01*
X1609473Y849471D01*
X1610565Y848305D01*
X1611220Y846846D01*
Y838388D01*
G01Y846846D02*
X1611875Y848305D01*
X1612966Y849471D01*
X1614495Y850054D01*
X1616023Y849471D01*
X1617115Y848305D01*
X1617770Y846555D01*
Y838388D01*
G01X1629812Y832555D02*
X1631995Y835471D01*
X1633087Y838388D01*
Y850054D01*
X1631995Y852971D01*
X1629812Y855888D01*
G01X1536417Y806362D02*
X1537726Y804904D01*
X1539255Y804030D01*
X1541220Y803738D01*
X1543185Y804321D01*
X1544713Y805488D01*
X1545805Y807529D01*
X1546023Y809863D01*
X1545587Y812196D01*
X1544495Y813655D01*
X1542966Y814821D01*
X1541438Y815113D01*
X1539910Y814821D01*
X1537945Y813655D01*
X1538600Y821238D01*
X1544495D01*
G01X1558720D02*
X1556973Y820655D01*
X1555663Y819196D01*
X1554790Y817447D01*
X1554135Y815113D01*
X1553917Y812488D01*
X1554135Y809863D01*
X1554790Y807529D01*
X1555663Y805779D01*
X1556973Y804321D01*
X1558720Y803738D01*
X1560466Y804321D01*
X1561777Y805779D01*
X1562650Y807529D01*
X1563305Y809863D01*
X1563523Y812488D01*
X1563305Y815113D01*
X1562650Y817447D01*
X1561777Y819196D01*
X1560466Y820655D01*
X1558720Y821238D01*
G01X1576220Y803155D02*
X1575783Y803446D01*
Y804030D01*
X1576220Y804321D01*
X1576657Y804030D01*
Y803446D01*
X1576220Y803155D01*
G01X1593720Y821238D02*
X1591973Y820655D01*
X1590663Y819196D01*
X1589790Y817447D01*
X1589135Y815113D01*
X1588917Y812488D01*
X1589135Y809863D01*
X1589790Y807529D01*
X1590663Y805779D01*
X1591973Y804321D01*
X1593720Y803738D01*
X1595466Y804321D01*
X1596777Y805779D01*
X1597650Y807529D01*
X1598305Y809863D01*
X1598523Y812488D01*
X1598305Y815113D01*
X1597650Y817447D01*
X1596777Y819196D01*
X1595466Y820655D01*
X1593720Y821238D01*
G01X1674670Y855888D02*
X1677726Y838388D01*
X1681220Y855888D01*
X1684713Y838388D01*
X1687770Y855888D01*
G01X1696100D02*
X1701340D01*
G01X1698720D02*
Y838388D01*
G01X1696100D02*
X1701340D01*
G01X1711417D02*
Y855888D01*
X1715783D01*
X1717530Y855013D01*
X1718840Y853846D01*
X1719932Y852097D01*
X1720805Y850054D01*
X1721023Y847138D01*
X1720805Y844221D01*
X1719932Y842179D01*
X1718840Y840429D01*
X1717530Y839263D01*
X1715783Y838388D01*
X1711417D01*
G01X1733720Y855888D02*
Y838388D01*
G01X1728698Y855888D02*
X1738742D01*
G01X1746635Y838388D02*
Y855888D01*
G01X1755805D02*
Y838388D01*
G01Y847138D02*
X1746635D01*
G01X1767628Y832555D02*
X1765445Y835471D01*
X1764353Y838388D01*
Y850054D01*
X1765445Y852971D01*
X1767628Y855888D01*
G01X1779670Y838388D02*
Y850054D01*
G01Y846846D02*
X1780325Y848305D01*
X1781417Y849471D01*
X1782945Y850054D01*
X1784473Y849471D01*
X1785565Y848305D01*
X1786220Y846846D01*
Y838388D01*
G01Y846846D02*
X1786875Y848305D01*
X1787966Y849471D01*
X1789495Y850054D01*
X1791023Y849471D01*
X1792115Y848305D01*
X1792770Y846555D01*
Y838388D01*
G01X1803720Y850054D02*
Y838388D01*
G01Y854721D02*
X1803283Y855013D01*
Y855596D01*
X1803720Y855888D01*
X1804157Y855596D01*
Y855013D01*
X1803720Y854721D01*
G01X1821220Y838388D02*
Y855888D01*
G01X1835445Y840429D02*
X1836537Y839263D01*
X1838065Y838388D01*
X1839375D01*
X1840685Y838971D01*
X1841558Y839846D01*
X1841995Y841012D01*
X1841777Y842763D01*
X1840903Y843638D01*
X1836973Y845388D01*
X1836100Y847430D01*
X1836537Y848888D01*
X1837410Y849763D01*
X1838720Y850054D01*
X1840030Y849763D01*
X1841340Y848888D01*
G01X1857312Y832555D02*
X1859495Y835471D01*
X1860587Y838388D01*
Y850054D01*
X1859495Y852971D01*
X1857312Y855888D01*
G01X1745090Y803738D02*
Y821238D01*
X1737011Y808696D01*
X1747929D01*
G01X1759970Y803155D02*
X1759533Y803446D01*
Y804030D01*
X1759970Y804321D01*
X1760407Y804030D01*
Y803446D01*
X1759970Y803155D01*
G01X1777033Y803738D02*
X1777470Y807529D01*
X1778125Y810738D01*
X1778998Y813655D01*
X1780090Y816863D01*
X1781837Y821238D01*
X1773103D01*
G01X1790167Y806362D02*
X1791476Y804904D01*
X1793005Y804030D01*
X1794970Y803738D01*
X1796935Y804321D01*
X1798463Y805488D01*
X1799555Y807529D01*
X1799773Y809863D01*
X1799337Y812196D01*
X1798245Y813655D01*
X1796716Y814821D01*
X1795188Y815113D01*
X1793660Y814821D01*
X1791695Y813655D01*
X1792350Y821238D01*
X1798245D01*
G01X1908720Y855888D02*
Y838388D01*
G01X1903698Y855888D02*
X1913742D01*
G01X1926220Y838388D02*
Y846263D01*
X1921853Y855888D01*
G01X1930587D02*
X1926220Y846263D01*
G01X1939353Y838388D02*
Y855888D01*
X1944593D01*
X1946340Y855013D01*
X1947650Y852971D01*
X1948087Y850638D01*
X1947650Y848305D01*
X1946558Y846555D01*
X1944593Y845679D01*
X1939353D01*
G01X1965587Y838388D02*
X1956853D01*
Y855888D01*
X1965587D01*
G01X1962093Y847430D02*
X1956853D01*
G01X1921635Y806071D02*
X1923382Y804613D01*
X1925347Y803738D01*
X1927093D01*
X1928840Y804613D01*
X1930150Y806071D01*
X1930805Y808113D01*
X1930368Y810154D01*
X1929277Y811905D01*
X1927312Y813071D01*
X1924692Y813655D01*
X1923163Y814821D01*
X1922508Y816863D01*
X1922945Y818905D01*
X1924037Y820363D01*
X1925565Y821238D01*
X1927093D01*
X1928622Y820655D01*
X1929932Y819196D01*
G01X1948087Y803738D02*
X1939353D01*
Y821238D01*
X1948087D01*
G01X1944593Y812780D02*
X1939353D01*
G01X2009353Y838388D02*
Y855888D01*
X2014812D01*
X2016558Y855013D01*
X2017650Y853846D01*
X2018087Y851513D01*
X2017650Y849179D01*
X2016340Y847721D01*
X2014812Y846846D01*
X2009353D01*
G01X2014812D02*
X2018087Y838388D01*
G01X2027945Y846263D02*
X2034932D01*
X2034277Y848305D01*
X2033185Y849471D01*
X2031657Y850054D01*
X2030128Y849763D01*
X2028818Y848888D01*
X2027945Y846846D01*
X2027508Y845096D01*
Y843346D01*
X2027945Y841596D01*
X2029037Y839846D01*
X2030347Y838680D01*
X2031875Y838388D01*
X2033403Y838971D01*
X2034932Y840721D01*
G01X2047410Y838388D02*
Y853263D01*
X2047847Y854721D01*
X2048720Y855596D01*
X2050030Y855888D01*
X2051340Y855305D01*
X2051995Y853846D01*
G01X2049375Y848888D02*
X2045008D01*
G01X2066220Y837805D02*
X2065783Y838096D01*
Y838680D01*
X2066220Y838971D01*
X2066657Y838680D01*
Y838096D01*
X2066220Y837805D01*
G01X2096853Y838388D02*
Y855888D01*
X2102093D01*
X2103840Y855013D01*
X2105150Y852971D01*
X2105587Y850638D01*
X2105150Y848305D01*
X2104058Y846555D01*
X2102093Y845679D01*
X2096853D01*
G01X2118720Y838388D02*
Y855888D01*
G01X2140150Y838388D02*
Y850054D01*
G01Y848013D02*
X2139277Y849179D01*
X2137966Y849763D01*
X2136438Y850054D01*
X2134910Y849471D01*
X2133600Y848305D01*
X2132726Y846555D01*
X2132290Y844221D01*
X2132726Y841888D01*
X2133600Y840138D01*
X2134910Y838971D01*
X2136438Y838388D01*
X2137966Y838680D01*
X2139277Y839554D01*
X2140150Y840721D01*
G01X2150008Y838388D02*
Y850054D01*
G01Y847138D02*
X2150882Y848596D01*
X2152192Y849763D01*
X2153938Y850054D01*
X2155466Y849763D01*
X2156777Y848596D01*
X2157432Y846555D01*
Y838388D01*
G01X2167945Y846263D02*
X2174932D01*
X2174277Y848305D01*
X2173185Y849471D01*
X2171657Y850054D01*
X2170128Y849763D01*
X2168818Y848888D01*
X2167945Y846846D01*
X2167508Y845096D01*
Y843346D01*
X2167945Y841596D01*
X2169037Y839846D01*
X2170347Y838680D01*
X2171875Y838388D01*
X2173403Y838971D01*
X2174932Y840721D01*
G01X2079353Y821238D02*
Y803738D01*
X2088087D01*
G01X2100783D02*
X2101220Y807529D01*
X2101875Y810738D01*
X2102748Y813655D01*
X2103840Y816863D01*
X2105587Y821238D01*
X2096853D01*
G01X2289020Y815404D02*
Y803738D01*
G01Y820071D02*
X2288583Y820363D01*
Y820946D01*
X2289020Y821238D01*
X2289457Y820946D01*
Y820363D01*
X2289020Y820071D01*
G01X2303245Y805779D02*
X2304337Y804613D01*
X2305865Y803738D01*
X2307175D01*
X2308485Y804321D01*
X2309358Y805196D01*
X2309795Y806362D01*
X2309577Y808113D01*
X2308703Y808988D01*
X2304773Y810738D01*
X2303900Y812780D01*
X2304337Y814238D01*
X2305210Y815113D01*
X2306520Y815404D01*
X2307830Y815113D01*
X2309140Y814238D01*
G01X2336498Y803738D02*
Y821238D01*
X2346542Y803738D01*
Y821238D01*
G01X2359020Y803738D02*
X2357273Y804030D01*
X2355745Y805196D01*
X2354435Y806946D01*
X2353561Y808988D01*
X2353125Y811321D01*
Y813655D01*
X2353561Y815988D01*
X2354435Y818030D01*
X2355745Y819779D01*
X2357273Y820946D01*
X2359020Y821238D01*
X2360766Y820946D01*
X2362295Y819779D01*
X2363605Y818030D01*
X2364479Y815988D01*
X2364915Y813655D01*
Y811321D01*
X2364479Y808988D01*
X2363605Y806946D01*
X2362295Y805196D01*
X2360766Y804030D01*
X2359020Y803738D01*
G01X2376520Y821238D02*
Y803738D01*
G01X2371498Y821238D02*
X2381542D01*
G01X2407808Y815404D02*
Y807238D01*
X2408682Y805196D01*
X2409992Y804030D01*
X2411520Y803738D01*
X2413048Y804030D01*
X2414358Y805196D01*
X2415232Y807238D01*
G01Y803738D02*
Y815404D01*
G01X2425745Y805779D02*
X2426837Y804613D01*
X2428365Y803738D01*
X2429675D01*
X2430985Y804321D01*
X2431858Y805196D01*
X2432295Y806362D01*
X2432077Y808113D01*
X2431203Y808988D01*
X2427273Y810738D01*
X2426400Y812780D01*
X2426837Y814238D01*
X2427710Y815113D01*
X2429020Y815404D01*
X2430330Y815113D01*
X2431640Y814238D01*
G01X2443245Y811613D02*
X2450232D01*
X2449577Y813655D01*
X2448485Y814821D01*
X2446957Y815404D01*
X2445428Y815113D01*
X2444118Y814238D01*
X2443245Y812196D01*
X2442808Y810446D01*
Y808696D01*
X2443245Y806946D01*
X2444337Y805196D01*
X2445647Y804030D01*
X2447175Y803738D01*
X2448703Y804321D01*
X2450232Y806071D01*
G01X2467950Y821238D02*
Y803738D01*
G01Y806362D02*
X2467077Y804904D01*
X2465766Y804030D01*
X2464238Y803738D01*
X2462492Y804321D01*
X2461182Y805779D01*
X2460308Y807529D01*
X2460090Y809571D01*
X2460308Y811613D01*
X2461182Y813363D01*
X2462492Y814821D01*
X2464238Y815404D01*
X2465766Y815113D01*
X2466858Y814529D01*
X2467950Y813363D01*
G01X2214217Y837805D02*
X2223823Y850638D01*
G01X2219020Y852971D02*
Y835471D01*
G01X2223823Y837805D02*
X2214217Y850638D01*
G01X2212470Y844221D02*
X2225570D01*
G01X2251182D02*
X2256858D01*
G01X2284217Y838388D02*
Y855888D01*
X2288583D01*
X2290330Y855013D01*
X2291640Y853846D01*
X2292732Y852097D01*
X2293605Y850054D01*
X2293823Y847138D01*
X2293605Y844221D01*
X2292732Y842179D01*
X2291640Y840429D01*
X2290330Y839263D01*
X2288583Y838388D01*
X2284217D01*
G01X2303245Y846263D02*
X2310232D01*
X2309577Y848305D01*
X2308485Y849471D01*
X2306957Y850054D01*
X2305428Y849763D01*
X2304118Y848888D01*
X2303245Y846846D01*
X2302808Y845096D01*
Y843346D01*
X2303245Y841596D01*
X2304337Y839846D01*
X2305647Y838680D01*
X2307175Y838388D01*
X2308703Y838971D01*
X2310232Y840721D01*
G01X2320308Y838388D02*
Y850054D01*
G01Y847138D02*
X2321182Y848596D01*
X2322492Y849763D01*
X2324238Y850054D01*
X2325766Y849763D01*
X2327077Y848596D01*
X2327732Y846555D01*
Y838388D01*
G01X2341520D02*
X2340210Y838680D01*
X2338900Y839846D01*
X2338026Y841888D01*
X2337590Y844221D01*
X2338026Y846555D01*
X2338900Y848596D01*
X2340210Y849763D01*
X2341520Y850054D01*
X2342830Y849763D01*
X2344140Y848596D01*
X2345013Y846555D01*
X2345232Y844221D01*
X2345013Y841888D01*
X2344140Y839846D01*
X2342830Y838680D01*
X2341520Y838388D01*
G01X2359020Y855888D02*
Y838388D01*
G01X2355963Y850054D02*
X2362077D01*
G01X2373245Y846263D02*
X2380232D01*
X2379577Y848305D01*
X2378485Y849471D01*
X2376957Y850054D01*
X2375428Y849763D01*
X2374118Y848888D01*
X2373245Y846846D01*
X2372808Y845096D01*
Y843346D01*
X2373245Y841596D01*
X2374337Y839846D01*
X2375647Y838680D01*
X2377175Y838388D01*
X2378703Y838971D01*
X2380232Y840721D01*
G01X2390745Y840429D02*
X2391837Y839263D01*
X2393365Y838388D01*
X2394675D01*
X2395985Y838971D01*
X2396858Y839846D01*
X2397295Y841012D01*
X2397077Y842763D01*
X2396203Y843638D01*
X2392273Y845388D01*
X2391400Y847430D01*
X2391837Y848888D01*
X2392710Y849763D01*
X2394020Y850054D01*
X2395330Y849763D01*
X2396640Y848888D01*
G01X2429020Y855888D02*
Y838388D01*
G01X2425963Y850054D02*
X2432077D01*
G01X2442808Y838388D02*
Y855888D01*
G01Y847430D02*
X2443900Y848888D01*
X2444992Y849763D01*
X2446738Y850054D01*
X2448048Y849763D01*
X2449577Y848596D01*
X2450232Y846846D01*
Y838388D01*
G01X2467950D02*
Y850054D01*
G01Y848013D02*
X2467077Y849179D01*
X2465766Y849763D01*
X2464238Y850054D01*
X2462710Y849471D01*
X2461400Y848305D01*
X2460526Y846555D01*
X2460090Y844221D01*
X2460526Y841888D01*
X2461400Y840138D01*
X2462710Y838971D01*
X2464238Y838388D01*
X2465766Y838680D01*
X2467077Y839554D01*
X2467950Y840721D01*
G01X2481520Y855888D02*
Y838388D01*
G01X2478463Y850054D02*
X2484577D01*
G01X2516520Y855888D02*
Y838388D01*
G01X2513463Y850054D02*
X2519577D01*
G01X2530308Y838388D02*
Y855888D01*
G01Y847430D02*
X2531400Y848888D01*
X2532492Y849763D01*
X2534238Y850054D01*
X2535548Y849763D01*
X2537077Y848596D01*
X2537732Y846846D01*
Y838388D01*
G01X2551520Y850054D02*
Y838388D01*
G01Y854721D02*
X2551083Y855013D01*
Y855596D01*
X2551520Y855888D01*
X2551957Y855596D01*
Y855013D01*
X2551520Y854721D01*
G01X2565745Y840429D02*
X2566837Y839263D01*
X2568365Y838388D01*
X2569675D01*
X2570985Y838971D01*
X2571858Y839846D01*
X2572295Y841012D01*
X2572077Y842763D01*
X2571203Y843638D01*
X2567273Y845388D01*
X2566400Y847430D01*
X2566837Y848888D01*
X2567710Y849763D01*
X2569020Y850054D01*
X2570330Y849763D01*
X2571640Y848888D01*
G01X2601400Y855888D02*
X2606640D01*
G01X2604020D02*
Y838388D01*
G01X2601400D02*
X2606640D01*
G01X2614970D02*
Y850054D01*
G01Y846846D02*
X2615625Y848305D01*
X2616717Y849471D01*
X2618245Y850054D01*
X2619773Y849471D01*
X2620865Y848305D01*
X2621520Y846846D01*
Y838388D01*
G01Y846846D02*
X2622175Y848305D01*
X2623266Y849471D01*
X2624795Y850054D01*
X2626323Y849471D01*
X2627415Y848305D01*
X2628070Y846555D01*
Y838388D01*
G01X2635090Y832555D02*
Y850054D01*
G01Y847430D02*
X2636182Y848888D01*
X2637273Y849763D01*
X2639020Y850054D01*
X2640548Y849763D01*
X2642077Y848305D01*
X2642732Y846263D01*
X2642950Y844221D01*
X2642732Y842179D01*
X2642077Y840138D01*
X2640766Y838971D01*
X2639020Y838388D01*
X2637492Y838680D01*
X2635963Y839554D01*
X2635090Y840721D01*
G01X2653245Y846263D02*
X2660232D01*
X2659577Y848305D01*
X2658485Y849471D01*
X2656957Y850054D01*
X2655428Y849763D01*
X2654118Y848888D01*
X2653245Y846846D01*
X2652808Y845096D01*
Y843346D01*
X2653245Y841596D01*
X2654337Y839846D01*
X2655647Y838680D01*
X2657175Y838388D01*
X2658703Y838971D01*
X2660232Y840721D01*
G01X2677950Y855888D02*
Y838388D01*
G01Y841012D02*
X2677077Y839554D01*
X2675766Y838680D01*
X2674238Y838388D01*
X2672492Y838971D01*
X2671182Y840429D01*
X2670308Y842179D01*
X2670090Y844221D01*
X2670308Y846263D01*
X2671182Y848013D01*
X2672492Y849471D01*
X2674238Y850054D01*
X2675766Y849763D01*
X2676858Y849179D01*
X2677950Y848013D01*
G01X2695450Y838388D02*
Y850054D01*
G01Y848013D02*
X2694577Y849179D01*
X2693266Y849763D01*
X2691738Y850054D01*
X2690210Y849471D01*
X2688900Y848305D01*
X2688026Y846555D01*
X2687590Y844221D01*
X2688026Y841888D01*
X2688900Y840138D01*
X2690210Y838971D01*
X2691738Y838388D01*
X2693266Y838680D01*
X2694577Y839554D01*
X2695450Y840721D01*
G01X2705308Y838388D02*
Y850054D01*
G01Y847138D02*
X2706182Y848596D01*
X2707492Y849763D01*
X2709238Y850054D01*
X2710766Y849763D01*
X2712077Y848596D01*
X2712732Y846555D01*
Y838388D01*
G01X2730013Y848596D02*
X2728485Y849763D01*
X2727175Y850054D01*
X2725428Y849471D01*
X2724118Y848305D01*
X2723245Y846263D01*
X2723026Y844221D01*
X2723245Y842179D01*
X2724118Y840429D01*
X2725428Y838971D01*
X2727175Y838388D01*
X2728703Y838971D01*
X2730013Y840138D01*
G01X2740745Y846263D02*
X2747732D01*
X2747077Y848305D01*
X2745985Y849471D01*
X2744457Y850054D01*
X2742928Y849763D01*
X2741618Y848888D01*
X2740745Y846846D01*
X2740308Y845096D01*
Y843346D01*
X2740745Y841596D01*
X2741837Y839846D01*
X2743147Y838680D01*
X2744675Y838388D01*
X2746203Y838971D01*
X2747732Y840721D01*
G01X1425733Y-51181D02*
X-29385D01*
G01X-33322Y-47244D02*
G03X-29385Y-51181I3937J0D01*
G01X-33322Y-47244D02*
Y893701D01*
G01X-7874Y102402D02*
Y212205D01*
G01Y102402D02*
G03X0Y94528I7874J0D01*
G01Y212205D02*
G03X-7874I-3937J0D01*
G01Y237402D02*
G03X0I3937J-1D01*
G01X-7874D02*
Y406693D01*
G01X0D02*
G03X-7874I-3937J0D01*
G01Y431890D02*
G03X0I3937J0D01*
G01X-7874D02*
Y601181D01*
G01X0D02*
G03X-7874I-3937J0D01*
G01Y626378D02*
Y795669D01*
G01Y626378D02*
G03X0I3937J0D01*
G01Y795669D02*
G03X-7874I-3937J0D01*
G01Y820866D02*
G03X0I3937J0D01*
G01X-7874Y844488D02*
Y820866D01*
G01X-3937Y848425D02*
G03X-7874Y844488I0J-3937D01*
G01X93307Y848425D02*
X-3937D01*
G01X-29385Y897638D02*
G03X-33322Y893701I0J-3937D01*
G01X-29385Y897638D02*
X93307D01*
G01X98425Y94528D02*
X0D01*
G01X1400000Y36220D02*
G03X1398031Y38189I-1969J0D01*
G01X1396654D01*
G02X1394685Y40157I0J1969D01*
G01Y71654D01*
G02X1396654Y73622I1969J-1D01*
G01X1398031D01*
G03X1400000Y75591I0J1969D01*
G01Y836614D01*
G03X1396063Y840551I-3937J0D01*
G01X1368504D01*
G02X1363386Y845669I0J5118D01*
G01Y871654D01*
G03X1361417Y873622I-1969J-1D01*
G01X1358268D01*
G02X1356299Y875591I0J1969D01*
G01Y892521D01*
X1352363Y897638D01*
X1218110D01*
X1214173Y892520D01*
Y875984D01*
G02X1205512I-4331J0D01*
G01Y892520D01*
X1201575Y897638D01*
X1029528D01*
X1025591Y892520D01*
Y875591D01*
G02X1023622Y873622I-1969J0D01*
G01X1020472D01*
G03X1018504Y871654I0J-1968D01*
G01Y845669D01*
G02X1013386Y840551I-5118J0D01*
G01X1008433D01*
G03X988748Y820866I0J-19685D01*
G01Y650669D01*
G02X983748Y645669I-5000J0D01*
G01X926819D01*
G02X921819Y650669I0J5000D01*
G01Y820866D01*
G03X902134Y840551I-19685J0D01*
G01X872441D01*
G02X867323Y845669I0J5118D01*
G01Y871654D01*
G03X865354Y873622I-1969J-1D01*
G01X862205D01*
G02X860236Y875591I0J1969D01*
G01Y892521D01*
X856300Y897638D01*
X722048D01*
X718110Y892519D01*
Y875984D01*
G02X709449I-4331J0D01*
G01Y892520D01*
X705512Y897638D01*
X533465D01*
X529528Y892520D01*
Y875591D01*
G02X527559Y873622I-1969J0D01*
G01X524409D01*
G03X522441Y871654I0J-1968D01*
G01Y845669D01*
G02X517323Y840551I-5118J0D01*
G01X455118D01*
G02X450000Y845669I0J5118D01*
G01Y871654D01*
G03X448031Y873622I-1968J0D01*
G01X444882D01*
G02X442913Y875591I0J1969D01*
G01Y892521D01*
X438977Y897638D01*
X304725D01*
X300787Y892519D01*
Y875984D01*
G02X292126I-4331J0D01*
G01Y892521D01*
X288190Y897638D01*
X116142D01*
X112205Y892520D01*
Y875591D01*
G02X110236Y873622I-1969J0D01*
G01X107087D01*
G03X105118Y871654I0J-1969D01*
G01Y845669D01*
G02X100000Y840551I-5118J0D01*
G01X3937D01*
G03X0Y836614I0J-3937D01*
G01Y110276D01*
G03X7874Y102402I7874J0D01*
G01X196654D01*
G02X204528Y94528I0J-7874D01*
G01Y7874D01*
G03X212402Y0I7874J0D01*
G01X471014D01*
G02X478888Y-7874I0J-7874D01*
G01Y-11811D01*
G03X486762Y-19685I7874J0D01*
G01X1302165D01*
G03X1306102Y-15748I0J3937D01*
G01Y-3937D01*
G02X1310039Y0I3937J0D01*
G01X1396063D01*
G03X1400000Y3937I0J3937D01*
G01Y36220D01*
G01X93307Y848425D02*
G03X97244Y852362I0J3937D01*
G01Y893701D02*
Y852362D01*
G01Y893701D02*
G03X93307Y897638I-3937J0D01*
G01X192717Y94528D02*
X123622D01*
G01Y102402D02*
G03Y94528I0J-3937D01*
G01X98425D02*
G03Y102402I0J3937D01*
G01X196654Y0D02*
G03X204528Y-7874I7874J0D01*
G01X196654Y0D02*
Y29961D01*
G01X204528D02*
G03X196654I-3937J0D01*
G01Y55157D02*
Y90591D01*
G01Y55157D02*
G03X204528I3937J0D01*
G01X196654Y90591D02*
G03X192717Y94528I-3937J0D01*
G01X232077Y-7874D02*
G03Y0I0J3937D01*
G01Y-7874D02*
X204528D01*
G01X434439D02*
X257274D01*
G01Y0D02*
G03Y-7874I0J-3937D01*
G01X365945Y38188D02*
G03X367914Y40156I0J1969D01*
G01X354134D02*
G03X356103Y38188I1969J1D01*
G01D02*
X365945D01*
G01X354134Y71653D02*
Y40156D01*
G01X367914Y71653D02*
G03X365945Y73621I-1969J-1D01*
G01X356103D02*
G03X354134Y71653I0J-1969D01*
G01X365945Y73621D02*
X356103D01*
G01X367914Y40156D02*
Y71653D01*
G01X434439Y-7874D02*
G03Y0I0J3937D01*
G01X471014Y-15748D02*
G03X463140Y-7874I-7874J0D01*
G01D02*
X459636D01*
G01Y0D02*
G03Y-7874I0J-3937D01*
G01X707234Y-27559D02*
X478888D01*
G01X471014Y-19685D02*
G03X478888Y-27559I7874J0D01*
G01X471014Y-19685D02*
Y-15748D01*
G01X870226Y-27559D02*
X732431D01*
G01Y-19685D02*
G03Y-27559I0J-3937D01*
G01X707234D02*
G03Y-19685I0J3937D01*
G01X870226Y-27559D02*
G03Y-19685I1J3937D01*
G01X1072589Y-27559D02*
X895423D01*
G01Y-19685D02*
G03Y-27559I0J-3937D01*
G01X1072589D02*
G03Y-19685I0J3937D01*
G01X1097785D02*
G03Y-27559I1J-3937D01*
G01X1336086Y-8662D02*
X1318701D01*
G03X1314764Y-12599I0J-3937D01*
G01Y-23622D01*
G02X1310827Y-27559I-3937J0D01*
G01X1097785D01*
G01X1336086Y-8662D02*
G03Y-1I0J4330D01*
G01X1361283D02*
G03Y-8662I0J-4330D01*
G01X1407874Y13026D02*
Y-4725D01*
G02X1403937Y-8662I-3937J0D01*
G01X1361283D01*
G01X1403937Y848425D02*
X1375197D01*
G01X1371260Y852362D02*
G03X1375197Y848425I3937J0D01*
G01X1371260Y852362D02*
Y893701D01*
G01X1375197Y897638D02*
G03X1371260Y893701I0J-3937D01*
G01X1375197Y897638D02*
X1425733D01*
G01X1407874Y30709D02*
Y219685D01*
G01X1400000Y30709D02*
G03X1407874I3937J0D01*
G01Y13026D02*
G03X1400000I-3937J-1D01*
G01X1407874Y219685D02*
G03X1400000I-3937J0D01*
G01Y244882D02*
G03X1407874I3937J0D01*
G01Y414173D02*
Y244882D01*
G01Y608661D02*
Y439370D01*
G01X1400000D02*
G03X1407874I3937J0D01*
G01Y414173D02*
G03X1400000I-3937J0D01*
G01X1407874Y608661D02*
G03X1400000I-3937J0D01*
G01Y626378D02*
G03X1407874I3937J0D01*
G01Y795669D02*
Y626378D01*
G01Y795669D02*
G03X1400000I-3937J0D01*
G01Y820866D02*
G03X1407874I3937J0D01*
G01Y844488D02*
Y820866D01*
G01Y844488D02*
G03X1403937Y848425I-3937J0D01*
G01X1429670Y893701D02*
Y-47244D01*
G01X1425733Y-51181D02*
G03X1429670Y-47244I0J3937D01*
G01Y893701D02*
G03X1425733Y897638I-3937J0D01*
G54D12*
G01X135000Y660000D02*
X25000D01*
G01D02*
X24000Y659000D01*
G01X40000Y671000D02*
X26300D01*
G01D02*
X26100Y671200D01*
G01X33062Y680062D02*
X29500Y676500D01*
G01X67400Y275100D02*
X61644D01*
G01D02*
X60872Y274328D01*
G01X35709Y426942D02*
X36651Y426000D01*
G01D02*
X41250D01*
G01X54903Y447003D02*
X67952Y433954D01*
G01X42700Y455127D02*
X66527Y431300D01*
G01X46087Y455819D02*
X54903Y447003D01*
G01X46500Y460300D02*
X58054D01*
G01D02*
X67796Y470042D01*
G01X42700Y490600D02*
Y455127D01*
G01X66854Y507824D02*
X61524D01*
G01D02*
X60150Y506450D01*
G01X61850Y515650D02*
Y510749D01*
G01D02*
X56602Y505501D01*
G01D02*
X56600D01*
G01D02*
Y505287D01*
G01D02*
X48302Y496989D01*
G01D02*
Y496202D01*
G01D02*
X42700Y490600D01*
G01X66850Y526900D02*
X61350Y532400D01*
G01D02*
Y532850D01*
G01D02*
X60300Y533900D01*
G01X61870Y515670D02*
X61850Y515650D01*
G01X63000Y558930D02*
X69208Y565138D01*
G01X43100Y670900D02*
X44025Y671825D01*
G01D02*
X56582D01*
G01D02*
X57332Y671075D01*
G01D02*
X58963D01*
G01D02*
X58964Y671074D01*
G01D02*
X61326D01*
G01D02*
X61327Y671075D01*
G01D02*
X138037D01*
G01X39900Y678100D02*
X41900Y676100D01*
G01D02*
X67521D01*
G01X33600Y675800D02*
X40184D01*
G01D02*
X41309Y674675D01*
G01D02*
X59395D01*
G01D02*
X60145Y673925D01*
G01D02*
X139219D01*
G01X137446Y669650D02*
X61918D01*
G01D02*
X61917Y669649D01*
G01D02*
X58373D01*
G01D02*
X58372Y669650D01*
G01D02*
X56741D01*
G01D02*
X55991Y670400D01*
G01D02*
X48700D01*
G01D02*
X47300Y669000D01*
G01D02*
X42000D01*
G01D02*
X40000Y671000D01*
G01X35766Y673178D02*
X36298Y673710D01*
G01D02*
X40258D01*
G01D02*
X40718Y673250D01*
G01D02*
X58600D01*
G01D02*
X59350Y672500D01*
G01D02*
X59554D01*
G01D02*
X59555Y672499D01*
G01D02*
X60735D01*
G01D02*
X60736Y672500D01*
G01D02*
X138628D01*
G01X47800Y666400D02*
X50190Y668790D01*
G01D02*
X55450D01*
G01D02*
X56015Y668225D01*
G01D02*
X57781D01*
G01D02*
X57782Y668224D01*
G01D02*
X62508D01*
G01D02*
X62509Y668225D01*
G01D02*
X136855D01*
G01X100438Y680062D02*
X33062D01*
G01X54200Y666800D02*
X57190D01*
G01D02*
X57191Y666799D01*
G01D02*
X63099D01*
G01D02*
X63100Y666800D01*
G01D02*
X136264D01*
G01X43600Y665700D02*
X45025Y664275D01*
G01D02*
X136773D01*
G01X135591Y661425D02*
X39575D01*
G01D02*
X34500Y666500D01*
G01X36624Y669155D02*
X42929Y662850D01*
G01D02*
X136182D01*
G01X42100Y684000D02*
X43075Y683025D01*
G01D02*
X48100D01*
G01D02*
X50650Y685575D01*
G01D02*
X98957D01*
G01X38000Y684000D02*
X40400Y681600D01*
G01D02*
X49300D01*
G01D02*
X51850Y684150D01*
G01D02*
X98366D01*
G01X101300Y687000D02*
X47700D01*
G01D02*
X45800Y685100D01*
G01X92250Y273940D02*
X94038D01*
G01D02*
X99167Y268811D01*
G01X92250Y280186D02*
Y273940D01*
G01X67400Y275100D02*
X72100D01*
G01X92907Y280765D02*
X92829D01*
G01D02*
X92250Y280186D01*
G01X105200Y284300D02*
X95700Y293800D01*
G01D02*
Y293900D01*
G01X98620Y285300D02*
X96304Y287616D01*
G01X89300Y312300D02*
Y298926D01*
G01D02*
X93438Y294788D01*
G01D02*
Y293462D01*
G01D02*
X95297Y291603D01*
G01D02*
Y288623D01*
G01D02*
X96304Y287616D01*
G01X91000Y311984D02*
Y299400D01*
G01D02*
X94323Y296077D01*
G01D02*
X105108D01*
G01X91858Y362733D02*
Y314858D01*
G01D02*
X89300Y312300D01*
G01X93487Y364856D02*
Y314471D01*
G01D02*
X91000Y311984D01*
G01X74008Y380583D02*
X91858Y362733D01*
G01X67952Y390391D02*
X93487Y364856D01*
G01X66527Y431300D02*
Y373592D01*
G01D02*
X67002Y373117D01*
G01D02*
X67003D01*
G01D02*
X79200Y360920D01*
G01D02*
Y357429D01*
G01D02*
X79455Y357174D01*
G01X72708Y382055D02*
X74008Y380755D01*
G01D02*
Y380583D01*
G01X84700Y396000D02*
X85100D01*
G01D02*
X99086Y409986D01*
G01X67952Y433954D02*
Y390391D01*
G01X80950Y478600D02*
X80900Y478650D01*
G01D02*
Y481000D01*
G01X96750Y476400D02*
X98250D01*
G01X96750Y472400D02*
X97287D01*
G01D02*
X104100Y479213D01*
G01X93250Y476400D02*
X89550Y472800D01*
G01D02*
X70554D01*
G01D02*
X67796Y470042D01*
G01X96750Y480400D02*
X99401D01*
G01X68600Y494400D02*
X67700Y495300D01*
G01D02*
Y499120D01*
G01X70750Y498500D02*
X70800Y498450D01*
G01D02*
Y496662D01*
G01D02*
X70750Y496612D01*
G01D02*
Y496550D01*
G01D02*
X68600Y494400D01*
G01X98294Y507170D02*
X97481Y507983D01*
G01D02*
X85733D01*
G01D02*
X84250Y506500D01*
G01X95437Y496084D02*
X101667D01*
G01X70358Y506552D02*
X69086Y507824D01*
G01D02*
X66854D01*
G01X98951Y500084D02*
X95437D01*
G01X97860Y511212D02*
X87538D01*
G01D02*
X84250Y514500D01*
G01Y502500D02*
Y502717D01*
G01D02*
X88091Y506558D01*
G01D02*
X96890D01*
G01D02*
X97703Y505745D01*
G01X80900Y481000D02*
X87875Y487975D01*
G01D02*
X102713D01*
G01X73858Y506552D02*
Y505167D01*
G01D02*
X70910Y502219D01*
G01X95437Y504084D02*
X102388D01*
G01X84250Y510500D02*
X85342Y509408D01*
G01D02*
X99221D01*
G01X97649Y527129D02*
X96786Y526266D01*
G01X96009Y517567D02*
X99032D01*
G01X74050Y545700D02*
X73700Y545350D01*
G01D02*
Y542600D01*
G01X74050Y545700D02*
X74850Y546500D01*
G01X68567Y531405D02*
X69705Y532543D01*
G01D02*
X69756D01*
G01D02*
X70750Y533537D01*
G01D02*
Y535000D01*
G01X74300Y533600D02*
X72900Y535000D01*
G01D02*
X70750D01*
G01X99785Y545681D02*
X95870D01*
G01X97753Y523925D02*
X89675D01*
G01D02*
X88700Y524900D01*
G01X102075Y529701D02*
X97351D01*
G01D02*
X96786Y530266D01*
G01X73900Y527050D02*
X74250Y526700D01*
G01D02*
Y522500D01*
G01X98197Y513567D02*
X96009D01*
G01X80750Y522500D02*
X77700D01*
G01X85925Y546500D02*
X88278Y548853D01*
G01X98242Y522398D02*
X84352D01*
G01D02*
X84250Y522500D01*
G01Y518500D02*
Y518541D01*
G01D02*
X86668Y520959D01*
G01D02*
X98819D01*
G01X80750Y530500D02*
X79417Y529167D01*
G01D02*
X69117D01*
G01D02*
X66850Y526900D01*
G01X88565Y532410D02*
X88792Y532637D01*
G01D02*
X109776D01*
G01X88565Y532410D02*
X86655Y530500D01*
G01D02*
X84250D01*
G01X99864Y549683D02*
X95872D01*
G01D02*
X95870Y549681D01*
G01X80750Y554500D02*
X77500D01*
G01X74850Y546500D02*
X80750D01*
G01X92360Y563260D02*
X98529Y557091D01*
G01X84072Y562789D02*
Y561952D01*
G01D02*
X85720Y560304D01*
G01D02*
Y560151D01*
G01D02*
X86797Y559074D01*
G01D02*
X86950D01*
G01D02*
X87608Y558416D01*
G01D02*
Y557685D01*
G01X73100Y553100D02*
X75750D01*
G01D02*
X76500Y552350D01*
G01D02*
X79250D01*
G01D02*
X80750Y550850D01*
G01D02*
Y550500D01*
G01X65381Y548719D02*
X69762Y553100D01*
G01D02*
X73100D01*
G01X84250Y550500D02*
X84841Y551091D01*
G01D02*
X88500D01*
G01D02*
X89126Y551717D01*
G01D02*
X89265D01*
G01D02*
X90576Y553028D01*
G01D02*
Y553167D01*
G01D02*
X91650Y554241D01*
G01D02*
X102559D01*
G01X69208Y565138D02*
X80097D01*
G01D02*
X80572Y564663D01*
G01D02*
Y562789D01*
G01D02*
Y558780D01*
G01D02*
X80712Y558640D01*
G01X88278Y548853D02*
X89717Y550292D01*
G01D02*
X89856D01*
G01D02*
X92001Y552437D01*
G01D02*
Y552492D01*
G01D02*
X102229D01*
G01X84250Y546500D02*
X85925D01*
G01X84250Y554500D02*
X84716Y554034D01*
G01D02*
X88322D01*
G01D02*
Y553955D01*
G01D02*
X88338D01*
G01X103150Y555666D02*
X90049D01*
G01D02*
X88338Y553955D01*
G01X84250Y554500D02*
Y558602D01*
G01D02*
X84212Y558640D01*
G01X67521Y676100D02*
X68046Y675575D01*
G01D02*
X139585D01*
G01X85800Y727500D02*
X81950D01*
G01D02*
X80150Y729300D01*
G01X72900Y729550D02*
X69350D01*
G01D02*
X68900Y730000D01*
G01X72900Y729550D02*
X76400D01*
G01D02*
X76650Y729300D01*
G01X72900Y733050D02*
X71644D01*
G01D02*
X68465Y736229D01*
G01X76650Y733300D02*
X73150D01*
G01D02*
X72900Y733050D01*
G01X80150Y733300D02*
X83500D01*
G01D02*
X85800Y731000D01*
G01X99167Y268811D02*
X101463D01*
G01X101950Y275460D02*
X105200Y278710D01*
G01X131236Y314736D02*
X116846Y300346D01*
G01D02*
X111393D01*
G01D02*
X105500Y294453D01*
G01D02*
Y291250D01*
G01X102499Y281183D02*
X99055D01*
G01D02*
X98588Y281650D01*
G01X105200Y278710D02*
Y284300D01*
G01X100500Y285300D02*
X98620D01*
G01X105108Y296077D02*
X110802Y301771D01*
G01D02*
X116255D01*
G01D02*
X129811Y315327D01*
G01X116906Y283244D02*
X115200Y284950D01*
G01D02*
Y287250D01*
G01D02*
X114350Y288100D01*
G01D02*
X114000Y287750D01*
G01D02*
X110000D01*
G01D02*
X105500D01*
G01X120700Y282400D02*
X117750D01*
G01D02*
X116906Y283244D01*
G01X107558Y321012D02*
X110746Y324200D01*
G01D02*
X111000D01*
G01D02*
X115938Y329138D01*
G01D02*
Y356938D01*
G01X134800Y328615D02*
X131236Y325051D01*
G01D02*
Y314736D01*
G01X102457Y347243D02*
X113000Y336700D01*
G01D02*
Y336000D01*
G01X129811Y315327D02*
Y327538D01*
G01D02*
X135873Y333600D01*
G01X115938Y356938D02*
X119650Y360650D01*
G01D02*
Y374390D01*
G01D02*
X125700Y380440D01*
G01X102457Y347690D02*
Y347243D01*
G01X113000Y387000D02*
Y359506D01*
G01D02*
X102457Y348963D01*
G01D02*
Y347690D01*
G01X125700Y380440D02*
Y383284D01*
G01D02*
X125718Y383302D01*
G01X99086Y409986D02*
Y415883D01*
G01X124290Y401910D02*
Y398290D01*
G01D02*
X113000Y387000D01*
G01X126122Y432323D02*
X128426Y434627D01*
G01D02*
X132204D01*
G01X114818Y433528D02*
Y434218D01*
G01D02*
X125363Y444763D01*
G01D02*
X130633D01*
G01X99086Y415883D02*
X105776Y422573D01*
G01D02*
Y424486D01*
G01D02*
X114818Y433528D01*
G01X130642Y470680D02*
X132110Y472148D01*
G01X128280Y476120D02*
X134272Y482112D01*
G01X124822Y488342D02*
X108102Y471628D01*
G01D02*
X105728D01*
G01X103500Y465026D02*
Y461250D01*
G01X126435Y487961D02*
X103500Y465026D01*
G01X98250Y476400D02*
X104969Y483119D01*
G01X127142Y459404D02*
Y452958D01*
G01D02*
X127820Y452280D01*
G01X127142Y470680D02*
Y459404D01*
G01X99401Y480400D02*
X105401Y486400D01*
G01D02*
X107863D01*
G01D02*
X115622Y494159D01*
G01D02*
X121010D01*
G01D02*
X121673Y494822D01*
G01X132524Y500900D02*
X129926D01*
G01D02*
X128610Y499584D01*
G01D02*
X126361D01*
G01D02*
X124823Y501122D01*
G01X106818Y513350D02*
X100638Y507170D01*
G01D02*
X98294D01*
G01X128450Y481470D02*
X130304D01*
G01D02*
X132734Y483900D01*
G01X127973Y510571D02*
X128418Y510126D01*
G01D02*
Y508018D01*
G01D02*
X128100Y507700D01*
G01X101667Y496084D02*
X105141Y499558D01*
G01D02*
Y499588D01*
G01D02*
X113500Y507947D01*
G01D02*
X126111D01*
G01D02*
X126358Y507700D01*
G01D02*
X128100D01*
G01X131718Y498682D02*
X128682D01*
G01D02*
X127973Y497973D01*
G01X100063Y498972D02*
X102539D01*
G01D02*
X112600Y509033D01*
G01D02*
X123285D01*
G01D02*
X124823Y510571D01*
G01X100063Y498972D02*
X98951Y500084D01*
G01X103604Y516550D02*
X98768Y511714D01*
G01D02*
Y511687D01*
G01D02*
X98727Y511646D01*
G01D02*
X98294D01*
G01D02*
X97860Y511212D01*
G01X117771Y499896D02*
X118997Y501122D01*
G01D02*
X121673D01*
G01X124822Y488523D02*
Y488342D01*
G01X106037Y507711D02*
X110509Y512183D01*
G01D02*
X123283D01*
G01D02*
X124821Y513721D01*
G01X97703Y505745D02*
X104071D01*
G01D02*
X106037Y507711D01*
G01X102713Y487975D02*
X112068Y497330D01*
G01D02*
X121030D01*
G01D02*
X121673Y497973D01*
G01X131122Y491674D02*
X129510Y490062D01*
G01D02*
X127336D01*
G01D02*
X126435Y489161D01*
G01D02*
Y487961D01*
G01X104969Y483119D02*
X105555D01*
G01D02*
X106752D01*
G01D02*
X116917Y493284D01*
G01D02*
X123285D01*
G01D02*
X124823Y494822D01*
G01X136638Y502300D02*
X129200D01*
G01D02*
X128022Y501122D01*
G01D02*
X127973D01*
G01X104100Y479213D02*
X105144D01*
G01D02*
X114881Y488950D01*
G01D02*
X117867D01*
G01X121673Y491672D02*
X118951Y488950D01*
G01D02*
X117867D01*
G01X102388Y504084D02*
X103055Y503417D01*
G01D02*
X105504D01*
G01D02*
X112658Y510571D01*
G01D02*
X121673D01*
G01X105552Y515598D02*
X99362Y509408D01*
G01D02*
X99221D01*
G01X107341Y528856D02*
X105337D01*
G01D02*
X103610Y527129D01*
G01D02*
X97649D01*
G01X131121Y523168D02*
X128706Y525583D01*
G01D02*
X111016D01*
G01D02*
X107743Y528856D01*
G01D02*
X107341D01*
G01X101821Y550159D02*
X113980Y538000D01*
G01D02*
X115956D01*
G01D02*
X121339Y532617D01*
G01D02*
X121673D01*
G01X99032Y517567D02*
X99768Y518303D01*
G01X124822Y520019D02*
X123285Y518482D01*
G01D02*
X110018D01*
G01D02*
X107388Y521112D01*
G01D02*
X102544D01*
G01D02*
X99768Y518336D01*
G01D02*
Y518303D01*
G01X131309Y539702D02*
X133705Y537306D01*
G01X129884Y566664D02*
Y534700D01*
G01D02*
X130384Y534200D01*
G01D02*
X133772D01*
G01X100270Y545196D02*
X99785Y545681D01*
G01X100270Y545196D02*
X100273Y545199D01*
G01D02*
X105495D01*
G01D02*
X113894Y536800D01*
G01D02*
X115315D01*
G01D02*
X121036Y531079D01*
G01D02*
X123211D01*
G01D02*
X124823Y529467D01*
G01X116439Y547024D02*
X117363Y546100D01*
G01D02*
X120788D01*
G01D02*
X121673Y545215D01*
G01X127973Y523170D02*
X126435Y524708D01*
G01D02*
X109835D01*
G01D02*
X108895Y525648D01*
G01D02*
X99476D01*
G01D02*
X97753Y523925D01*
G01X131121Y529467D02*
X128405Y526751D01*
G01D02*
X112955D01*
G01D02*
X108494Y531212D01*
G01D02*
X103586D01*
G01D02*
X102075Y529701D01*
G01X121673Y513721D02*
X107189D01*
G01D02*
X106818Y513350D01*
G01X106575Y518876D02*
X106119Y519332D01*
G01D02*
X103962D01*
G01D02*
X98197Y513567D01*
G01X127971Y520018D02*
X125560Y517607D01*
G01D02*
X107844D01*
G01D02*
X106575Y518876D01*
G01X115100Y541700D02*
X116988Y539812D01*
G01D02*
X117468D01*
G01D02*
X121514Y535766D01*
G01D02*
X121673D01*
G01X102559Y554241D02*
X115100Y541700D01*
G01X130200Y517000D02*
X131121Y517921D01*
G01D02*
Y520018D01*
G01X130200Y517000D02*
X128459Y515259D01*
G01D02*
X127671D01*
G01D02*
X126380Y516550D01*
G01D02*
X103604D01*
G01X105926Y547851D02*
X114484Y539293D01*
G01D02*
X115971D01*
G01D02*
X121036Y534228D01*
G01D02*
X123212D01*
G01D02*
X124823Y532617D01*
G01Y523170D02*
X123285Y521632D01*
G01D02*
X121036D01*
G01D02*
X119526Y523142D01*
G01D02*
X107996D01*
G01D02*
X106972Y524166D01*
G01D02*
X100010D01*
G01D02*
X98242Y522398D01*
G01X113757Y520886D02*
X118954D01*
G01D02*
X120073Y519767D01*
G01D02*
X121673D01*
G01D02*
Y520020D01*
G01X98819Y520959D02*
X100601Y522741D01*
G01D02*
X107159D01*
G01D02*
X109014Y520886D01*
G01D02*
X113757D01*
G01X128459Y565188D02*
Y544728D01*
G01D02*
X126435Y542704D01*
G01D02*
Y531981D01*
G01D02*
X127336Y531080D01*
G01D02*
X132500D01*
G01X109776Y532637D02*
X114484Y527929D01*
G01D02*
X126433D01*
G01D02*
X127973Y529469D01*
G01X121673Y538916D02*
X116489Y544100D01*
G01D02*
X114716D01*
G01D02*
X103150Y555666D01*
G01X127971Y513721D02*
X126094Y515598D01*
G01D02*
X105552D01*
G01X110574Y597870D02*
Y559648D01*
G01D02*
X111922Y558300D01*
G01D02*
X120172D01*
G01D02*
X122010Y556462D01*
G01D02*
X124900D01*
G01X117699Y588674D02*
Y573932D01*
G01D02*
X122434Y569197D01*
G01D02*
Y567741D01*
G01D02*
X122547Y567628D01*
G01X114849Y595349D02*
Y569692D01*
G01D02*
X116037Y568504D01*
G01D02*
X116709D01*
G01D02*
X117566Y569361D01*
G01D02*
X118238D01*
G01D02*
X118910Y568689D01*
G01D02*
Y568017D01*
G01D02*
X118053Y567160D01*
G01D02*
Y566488D01*
G01D02*
X121727Y562814D01*
G01D02*
X124900D01*
G01X111999Y597099D02*
Y564000D01*
G01D02*
X112499Y563500D01*
G01D02*
X117000D01*
G01D02*
X117500Y563000D01*
G01D02*
Y562200D01*
G01D02*
X117000Y561700D01*
G01D02*
X112600D01*
G01D02*
X112100Y561200D01*
G01D02*
Y560138D01*
G01D02*
X112600Y559638D01*
G01D02*
X124900D01*
G01X109149Y598700D02*
Y558575D01*
G01D02*
X111024Y556700D01*
G01D02*
X114982D01*
G01D02*
X115482Y556200D01*
G01D02*
Y555399D01*
G01D02*
X115957Y554924D01*
G01D02*
X116907D01*
G01D02*
X117382Y555399D01*
G01D02*
Y556200D01*
G01D02*
X117882Y556700D01*
G01D02*
X118782D01*
G01D02*
X119282Y556200D01*
G01D02*
Y555399D01*
G01D02*
X119757Y554924D01*
G01D02*
X122547D01*
G01X113424Y596146D02*
Y569101D01*
G01D02*
X121249Y561276D01*
G01D02*
X122547D01*
G01X100350Y550196D02*
Y550159D01*
G01D02*
X101821D01*
G01X100350Y550196D02*
X100341Y550187D01*
G01D02*
Y550160D01*
G01D02*
X99864Y549683D01*
G01X127802Y581799D02*
X129884Y579716D01*
G01D02*
Y578884D01*
G01D02*
X129403Y578403D01*
G01D02*
X128697D01*
G01D02*
X127200Y579899D01*
G01D02*
X122700D01*
G01D02*
X122200Y579399D01*
G01D02*
Y578548D01*
G01D02*
X122848Y577900D01*
G01D02*
X124563D01*
G01D02*
X125100Y577363D01*
G01D02*
Y575284D01*
G01D02*
X125000Y575184D01*
G01D02*
Y573588D01*
G01D02*
X125988Y572600D01*
G01D02*
X130809D01*
G01D02*
X131309Y572100D01*
G01X120549Y584649D02*
Y578196D01*
G01D02*
X120775Y577970D01*
G01D02*
Y577957D01*
G01D02*
X122257Y576475D01*
G01D02*
X122270D01*
G01D02*
X123532Y575213D01*
G01D02*
Y573016D01*
G01D02*
X129884Y566664D01*
G01X98529Y557091D02*
X104073D01*
G01D02*
X113689Y547475D01*
G01D02*
X115988D01*
G01D02*
X116439Y547024D01*
G01X131309Y575209D02*
X130486Y574386D01*
G01D02*
X126801D01*
G01X116274Y591724D02*
Y573341D01*
G01D02*
X121009Y568606D01*
G01D02*
Y566708D01*
G01D02*
X121727Y565990D01*
G01D02*
X124900D01*
G01X102229Y552492D02*
X105926Y548795D01*
G01D02*
Y547851D01*
G01X106299Y604771D02*
Y556701D01*
G01D02*
X111300Y551700D01*
G01D02*
X116600D01*
G01D02*
X118190Y550110D01*
G01D02*
X124847D01*
G01X119124Y587924D02*
Y574523D01*
G01D02*
X128459Y565188D01*
G01X107724Y603018D02*
Y557416D01*
G01D02*
X111854Y553286D01*
G01D02*
X118006D01*
G01D02*
X118481Y552811D01*
G01D02*
Y552075D01*
G01D02*
X118956Y551600D01*
G01D02*
X119906D01*
G01D02*
X120381Y552075D01*
G01D02*
Y552811D01*
G01D02*
X120856Y553286D01*
G01D02*
X124900D01*
G01X115622Y601496D02*
X114200D01*
G01D02*
X110574Y597870D01*
G01X118773Y589748D02*
X117699Y588674D01*
G01X118773Y598345D02*
X117845D01*
G01D02*
X114849Y595349D01*
G01X118773Y601495D02*
X117161Y599883D01*
G01D02*
X114783D01*
G01D02*
X111999Y597099D01*
G01X118773Y610945D02*
X117000D01*
G01D02*
X116500Y610445D01*
G01D02*
Y609000D01*
G01D02*
X117000Y608500D01*
G01D02*
X120000D01*
G01D02*
X120500Y608000D01*
G01D02*
Y606700D01*
G01D02*
X120000Y606200D01*
G01D02*
X114114D01*
G01D02*
X113614Y605700D01*
G01D02*
Y603165D01*
G01D02*
X109149Y598700D01*
G01X131370Y601496D02*
X131700Y601166D01*
G01X115623Y598345D02*
X113424Y596146D01*
G01X125070Y598347D02*
X125063Y598340D01*
G01D02*
Y584200D01*
G01D02*
X124673Y583810D01*
G01D02*
X122310D01*
G01D02*
X121974Y583474D01*
G01D02*
Y582200D01*
G01D02*
X122375Y581799D01*
G01D02*
X127802D01*
G01X120343Y615248D02*
Y612995D01*
G01D02*
X120800Y612538D01*
G01D02*
X122862D01*
G01D02*
X123532Y611868D01*
G01D02*
Y587632D01*
G01D02*
X120549Y584649D01*
G01X125072Y610945D02*
Y600520D01*
G01D02*
X126608Y598984D01*
G01D02*
Y585009D01*
G01D02*
X131309Y580308D01*
G01X118773Y604645D02*
X120311Y603107D01*
G01D02*
Y594561D01*
G01D02*
X119408Y593658D01*
G01D02*
X118208D01*
G01D02*
X116274Y591724D01*
G01X128221Y610945D02*
Y609679D01*
G01D02*
X129832Y608068D01*
G01D02*
Y600859D01*
G01D02*
X130600Y600091D01*
G01D02*
Y591842D01*
G01D02*
X133563Y588879D01*
G01X115622Y614094D02*
X106299Y604771D01*
G01X131369Y614095D02*
X129759Y612485D01*
G01D02*
Y610380D01*
G01D02*
X132983Y607156D01*
G01X121922Y610945D02*
X121549Y610572D01*
G01D02*
Y593850D01*
G01D02*
X120311Y592612D01*
G01D02*
Y589111D01*
G01D02*
X119124Y587924D01*
G01X128220Y614095D02*
X126683Y612558D01*
G01D02*
Y609117D01*
G01D02*
X128184Y607616D01*
G01D02*
Y600316D01*
G01D02*
X129458Y599042D01*
G01D02*
Y586455D01*
G01D02*
X136295Y579618D01*
G01X126646Y606400D02*
Y600184D01*
G01D02*
X128033Y598797D01*
G01D02*
Y585600D01*
G01D02*
X132734Y580899D01*
G01X118805Y614099D02*
X114571Y609865D01*
G01D02*
Y609193D01*
G01D02*
X115278Y608486D01*
G01D02*
Y607778D01*
G01D02*
X114642Y607142D01*
G01D02*
X113934D01*
G01D02*
X113227Y607849D01*
G01D02*
X112555D01*
G01D02*
X110790Y606084D01*
G01D02*
Y605412D01*
G01D02*
X112065Y604137D01*
G01D02*
Y603465D01*
G01D02*
X111393Y602793D01*
G01D02*
X110721D01*
G01D02*
X109446Y604068D01*
G01D02*
X108774D01*
G01D02*
X107724Y603018D01*
G01X125070Y614095D02*
Y615330D01*
G01D02*
X124695Y615705D01*
G01D02*
X120800D01*
G01D02*
X120343Y615248D01*
G01X98957Y685575D02*
X104682Y679850D01*
G01D02*
X156365D01*
G01X98366Y684150D02*
X104091Y678425D01*
G01D02*
X156956D01*
G01X157547Y677000D02*
X103500D01*
G01D02*
X100438Y680062D01*
G01X158768Y684300D02*
X104000D01*
G01D02*
X101300Y687000D01*
G01X171100Y252828D02*
X163900Y260028D01*
G01D02*
Y298400D01*
G01X162300Y306110D02*
Y257999D01*
G01D02*
X165162Y255137D01*
G01X163900Y298400D02*
X167500Y302000D01*
G01X165500Y309310D02*
X162300Y306110D01*
G01X134800Y329600D02*
Y328615D01*
G01X135873Y333600D02*
X160669D01*
G01D02*
X165500Y328769D01*
G01X132204Y434627D02*
X134683D01*
G01D02*
X135158Y434152D01*
G01D02*
Y430365D01*
G01X139096Y430391D02*
X135184D01*
G01D02*
X135158Y430365D01*
G01X142596Y430391D02*
Y437081D01*
G01D02*
X145901Y440386D01*
G01D02*
Y441262D01*
G01X134587Y443980D02*
X137344Y446737D01*
G01X135159Y426337D02*
Y424775D01*
G01D02*
X137136Y422798D01*
G01X153100Y439000D02*
X148500D01*
G01D02*
X146086Y436586D01*
G01D02*
Y428854D01*
G01D02*
X140030Y422798D01*
G01D02*
X137136D01*
G01X157931Y481369D02*
X161600Y477700D01*
G01D02*
Y472813D01*
G01D02*
X165000Y469413D01*
G01D02*
Y468000D01*
G01X157500D02*
X153878Y471622D01*
G01D02*
Y474653D01*
G01D02*
X151631Y476900D01*
G01D02*
Y486986D01*
G01X159434Y475345D02*
X156319Y478460D01*
G01D02*
Y485374D01*
G01X164000Y461250D02*
X162488Y462762D01*
G01D02*
Y469852D01*
G01D02*
X159434Y472906D01*
G01D02*
Y475345D01*
G01X157500Y458000D02*
X161063Y461563D01*
G01D02*
Y469685D01*
G01D02*
X156390Y474358D01*
G01D02*
Y475891D01*
G01D02*
X154781Y477500D01*
G01D02*
Y486986D01*
G01X133589Y477613D02*
X135883Y479907D01*
G01X132110Y472148D02*
Y476134D01*
G01D02*
X133589Y477613D01*
G01X164000Y457750D02*
X166085D01*
G01X168563Y469995D02*
X163800Y474758D01*
G01D02*
Y480500D01*
G01X157500Y463000D02*
X159638Y465138D01*
G01D02*
Y469115D01*
G01D02*
X155379Y473374D01*
G01D02*
Y474990D01*
G01D02*
X153169Y477200D01*
G01D02*
Y485374D01*
G01X134500Y466000D02*
Y475500D01*
G01D02*
X135727Y476727D01*
G01D02*
Y478499D01*
G01D02*
X135720Y478506D01*
G01D02*
X136758Y479544D01*
G01X137000Y457750D02*
X135040Y455790D01*
G01D02*
Y453700D01*
G01D02*
X137000Y451740D01*
G01D02*
Y451300D01*
G01X133440Y449150D02*
X134850D01*
G01D02*
X137000Y451300D01*
G01X139500Y466500D02*
X138508Y467492D01*
G01D02*
Y483048D01*
G01X137000Y461250D02*
X136467Y460717D01*
G01D02*
X132967D01*
G01D02*
X132959Y460709D01*
G01X137633Y479181D02*
X137000Y478548D01*
G01D02*
Y461250D01*
G01X167138Y469686D02*
X162700Y474124D01*
G01D02*
Y478900D01*
G01D02*
X159469Y482131D01*
G01X165000Y486142D02*
Y476558D01*
G01D02*
X171000Y470558D01*
G01X159469Y488524D02*
X157931Y486986D01*
G01D02*
Y481369D01*
G01X151631Y486986D02*
X153169Y488524D01*
G01X154781Y486986D02*
X156318Y488523D01*
G01X135883Y479907D02*
Y486986D01*
G01D02*
X137421Y488524D01*
G01X150020Y491674D02*
X150100Y491754D01*
G01D02*
Y494700D01*
G01X136272Y496478D02*
X134275Y498475D01*
G01D02*
Y499075D01*
G01D02*
X133856Y499494D01*
G01D02*
Y499568D01*
G01D02*
X132524Y500900D01*
G01X163800Y480500D02*
X161080Y483220D01*
G01D02*
Y490136D01*
G01D02*
X162618Y491674D01*
G01X161500Y498250D02*
Y497551D01*
G01D02*
X164371Y494680D01*
G01D02*
X164937D01*
G01D02*
X167306Y492311D01*
G01X132734Y483900D02*
Y486986D01*
G01D02*
X134272Y488524D01*
G01X136758Y479544D02*
Y484711D01*
G01D02*
X137421Y485374D01*
G01X138508Y483048D02*
X140571Y485111D01*
G01D02*
Y485374D01*
G01X134272Y482112D02*
Y485374D01*
G01X140570Y488523D02*
X139033Y486986D01*
G01D02*
Y485000D01*
G01D02*
X138959Y484926D01*
G01D02*
Y484737D01*
G01D02*
X137633Y483411D01*
G01D02*
Y479181D01*
G01X159469Y482131D02*
Y485374D01*
G01X162618Y488524D02*
X165000Y486142D01*
G01X137600Y501338D02*
X136638Y502300D01*
G01X139145Y580800D02*
Y543790D01*
G01D02*
X137421Y542066D01*
G01X131309Y572100D02*
Y539702D01*
G01X133705Y537306D02*
X135883D01*
G01D02*
X137421Y535768D01*
G01X133772Y534200D02*
X134272Y534700D01*
G01D02*
Y535768D01*
G01X159162Y550262D02*
X149355Y540455D01*
G01D02*
X149344D01*
G01D02*
X148443Y539554D01*
G01D02*
Y535152D01*
G01D02*
X147495Y534204D01*
G01D02*
X144796D01*
G01D02*
X143718Y535282D01*
G01D02*
Y538953D01*
G01X145025Y548000D02*
X146512Y546513D01*
G01D02*
Y545412D01*
G01D02*
X146100Y545000D01*
G01D02*
X143350D01*
G01D02*
X142850Y545500D01*
G01D02*
Y550935D01*
G01X150400Y547300D02*
Y544938D01*
G01D02*
X149437Y543975D01*
G01D02*
X143124D01*
G01D02*
X142148Y542999D01*
G01D02*
Y534195D01*
G01D02*
X140571Y532618D01*
G01X137720Y580209D02*
Y544737D01*
G01D02*
X135883Y542900D01*
G01D02*
Y540456D01*
G01D02*
X137421Y538918D01*
G01X165864Y533933D02*
X164549Y532618D01*
G01D02*
X162618D01*
G01X157737Y551037D02*
X148770Y542070D01*
G01D02*
X143686D01*
G01X140570Y557493D02*
Y535767D01*
G01X132500Y531080D02*
X133000Y530580D01*
G01D02*
Y529500D01*
G01D02*
X133500Y529000D01*
G01D02*
X136921D01*
G01D02*
X137421Y529500D01*
G01D02*
Y532618D01*
G01X136295Y546847D02*
Y545972D01*
G01D02*
X134272Y543949D01*
G01D02*
Y542066D01*
G01X132734Y580899D02*
Y540452D01*
G01D02*
X134270Y538916D01*
G01X157475Y587325D02*
Y564509D01*
G01D02*
X159162Y562822D01*
G01D02*
Y550262D01*
G01X131309Y580308D02*
Y575209D01*
G01X143268Y580709D02*
Y568132D01*
G01D02*
X144263Y567137D01*
G01D02*
X147900D01*
G01D02*
X148400Y566637D01*
G01D02*
Y560100D01*
G01D02*
X147900Y559600D01*
G01D02*
X145400D01*
G01D02*
X145025Y559225D01*
G01D02*
Y548000D01*
G01X142850Y550935D02*
X142951Y551036D01*
G01X144693Y581300D02*
Y569507D01*
G01D02*
X145638Y568562D01*
G01D02*
X148900D01*
G01D02*
X149836Y567626D01*
G01D02*
Y558836D01*
G01D02*
X149200Y558200D01*
G01D02*
X146900D01*
G01D02*
X145900Y557200D01*
G01D02*
Y548500D01*
G01D02*
X146600Y547800D01*
G01D02*
X149900D01*
G01D02*
X150400Y547300D01*
G01X133563Y584366D02*
X137720Y580209D01*
G01X160325Y589264D02*
Y567255D01*
G01D02*
X161280Y566300D01*
G01X156050Y585850D02*
Y563918D01*
G01D02*
X157737Y562231D01*
G01D02*
Y551037D01*
G01X140570Y581391D02*
Y564143D01*
G01D02*
X141045Y563668D01*
G01D02*
X145900D01*
G01D02*
X146400Y563168D01*
G01D02*
Y562268D01*
G01D02*
X145900Y561768D01*
G01D02*
X141045D01*
G01D02*
X140570Y561293D01*
G01D02*
Y560343D01*
G01D02*
X141045Y559868D01*
G01D02*
X143325D01*
G01D02*
X143800Y559393D01*
G01D02*
Y558443D01*
G01D02*
X143325Y557968D01*
G01D02*
X141045D01*
G01D02*
X140570Y557493D01*
G01X158900Y588100D02*
Y565100D01*
G01D02*
X160000Y564000D01*
G01D02*
X161280D01*
G01X136295Y579618D02*
Y576297D01*
G01D02*
X135820Y575822D01*
G01D02*
X134875D01*
G01D02*
X134400Y575347D01*
G01D02*
Y574397D01*
G01D02*
X134875Y573922D01*
G01D02*
X135820D01*
G01D02*
X136295Y573447D01*
G01D02*
Y572497D01*
G01D02*
X135820Y572022D01*
G01D02*
X134875D01*
G01D02*
X134400Y571547D01*
G01D02*
Y570597D01*
G01D02*
X134875Y570122D01*
G01D02*
X135820D01*
G01D02*
X136295Y569647D01*
G01D02*
Y568697D01*
G01D02*
X135820Y568222D01*
G01D02*
X134875D01*
G01D02*
X134400Y567747D01*
G01D02*
Y566797D01*
G01D02*
X134875Y566322D01*
G01D02*
X135820D01*
G01D02*
X136295Y565847D01*
G01D02*
Y564897D01*
G01D02*
X135820Y564422D01*
G01D02*
X134875D01*
G01D02*
X134400Y563947D01*
G01D02*
Y562997D01*
G01D02*
X134875Y562522D01*
G01D02*
X135820D01*
G01D02*
X136295Y562047D01*
G01D02*
Y561097D01*
G01D02*
X135820Y560622D01*
G01D02*
X134875D01*
G01D02*
X134400Y560147D01*
G01D02*
Y559197D01*
G01D02*
X134875Y558722D01*
G01D02*
X135820D01*
G01D02*
X136295Y558247D01*
G01D02*
Y557297D01*
G01D02*
X135820Y556822D01*
G01D02*
X134875D01*
G01D02*
X134400Y556347D01*
G01D02*
Y555397D01*
G01D02*
X134875Y554922D01*
G01D02*
X135820D01*
G01D02*
X136295Y554447D01*
G01D02*
Y553497D01*
G01D02*
X135820Y553022D01*
G01D02*
X134875D01*
G01D02*
X134400Y552547D01*
G01D02*
Y551597D01*
G01D02*
X134875Y551122D01*
G01D02*
X135820D01*
G01D02*
X136295Y550647D01*
G01D02*
Y549697D01*
G01D02*
X135820Y549222D01*
G01D02*
X134875D01*
G01D02*
X134400Y548747D01*
G01D02*
Y547797D01*
G01D02*
X134875Y547322D01*
G01D02*
X135820D01*
G01D02*
X136295Y546847D01*
G01X131700Y601166D02*
Y592588D01*
G01D02*
X134988Y589300D01*
G01D02*
Y584957D01*
G01D02*
X139145Y580800D01*
G01X140818Y610945D02*
X142357Y609406D01*
G01D02*
X150494D01*
G01D02*
X155700Y604200D01*
G01D02*
Y589100D01*
G01D02*
X157475Y587325D01*
G01X134521Y595196D02*
X137838Y591879D01*
G01D02*
Y586139D01*
G01D02*
X143268Y580709D01*
G01X132981Y614732D02*
Y610900D01*
G01D02*
X132982Y610899D01*
G01D02*
Y610307D01*
G01D02*
X134463Y608826D01*
G01D02*
Y600578D01*
G01D02*
X138306Y596735D01*
G01D02*
X138307D01*
G01D02*
X139263Y595779D01*
G01D02*
Y586730D01*
G01D02*
X144693Y581300D01*
G01X133563Y588879D02*
Y584366D01*
G01X151879Y614660D02*
Y613458D01*
G01D02*
X152854Y612483D01*
G01D02*
X154054D01*
G01D02*
X154955Y611582D01*
G01D02*
Y608945D01*
G01D02*
X158178Y605722D01*
G01D02*
Y591411D01*
G01D02*
X160325Y589264D01*
G01X134520Y610944D02*
X137564Y607900D01*
G01D02*
X139892D01*
G01D02*
X140367Y607425D01*
G01D02*
Y604475D01*
G01D02*
X140842Y604000D01*
G01D02*
X141792D01*
G01D02*
X142267Y604475D01*
G01D02*
Y607425D01*
G01D02*
X142742Y607900D01*
G01D02*
X143692D01*
G01D02*
X144167Y607425D01*
G01D02*
Y604475D01*
G01D02*
X144642Y604000D01*
G01D02*
X150680D01*
G01D02*
X151880Y602800D01*
G01D02*
Y590020D01*
G01D02*
X156050Y585850D01*
G01X132983Y607156D02*
Y593321D01*
G01D02*
X136413Y589891D01*
G01D02*
Y585548D01*
G01D02*
X140570Y581391D01*
G01X137669Y610945D02*
X139207Y612483D01*
G01D02*
X150904D01*
G01D02*
X151879Y611508D01*
G01D02*
Y610308D01*
G01D02*
X152780Y609407D01*
G01D02*
X152793D01*
G01D02*
X157000Y605200D01*
G01D02*
Y590000D01*
G01D02*
X158900Y588100D01*
G01X134521Y617266D02*
Y616272D01*
G01D02*
X132981Y614732D01*
G01X134519Y614095D02*
X136068Y615644D01*
G01D02*
X150895D01*
G01D02*
X151879Y614660D01*
G01X138037Y671075D02*
X142650Y666462D01*
G01D02*
X205961D01*
G01X139585Y675575D02*
X140747Y674413D01*
G01D02*
X187371D01*
G01X156365Y679850D02*
X162090Y685575D01*
G01X205370Y667887D02*
X164813D01*
G01D02*
X164400Y668300D01*
G01X176500Y656000D02*
X139000D01*
G01D02*
X135000Y660000D01*
G01X139219Y673925D02*
X141294Y671850D01*
G01D02*
X187918D01*
G01X206552Y665037D02*
X142059D01*
G01D02*
X137446Y669650D01*
G01X138628Y672500D02*
X140703Y670425D01*
G01D02*
X187327D01*
G01X136855Y668225D02*
X141468Y663612D01*
G01D02*
X207143D01*
G01X156956Y678425D02*
X162681Y684150D01*
G01X163272Y682725D02*
X157547Y677000D01*
G01X136264Y666800D02*
X140877Y662187D01*
G01D02*
X207734D01*
G01X136773Y664275D02*
X140286Y660762D01*
G01D02*
X208325D01*
G01X209507Y657912D02*
X139104D01*
G01D02*
X135591Y661425D01*
G01X136182Y662850D02*
X139695Y659337D01*
G01D02*
X208916D01*
G01X194585Y693463D02*
X164537D01*
G01D02*
X164500Y693500D01*
G01X162090Y685575D02*
X162091D01*
G01D02*
X167129Y690613D01*
G01X162681Y684150D02*
X168444D01*
G01X182481Y682725D02*
X163272D01*
G01X166506Y692038D02*
X158768Y684300D01*
G01X164575Y879791D02*
Y845575D01*
G01D02*
X164574Y845574D01*
G01D02*
Y835261D01*
G01D02*
X188335Y811500D01*
G01X153150Y889470D02*
Y837054D01*
G01D02*
X187204Y803000D01*
G01X162599Y889470D02*
Y834401D01*
G01D02*
X187725Y809275D01*
G01X155575Y880291D02*
Y848527D01*
G01D02*
X155574Y848526D01*
G01D02*
Y836646D01*
G01D02*
X187220Y805000D01*
G01X157000Y879700D02*
Y837236D01*
G01D02*
X187236Y807000D01*
G01X165748Y880964D02*
X164575Y879791D01*
G01X156300Y889470D02*
Y881016D01*
G01D02*
X155575Y880291D01*
G01X159449Y889470D02*
Y882149D01*
G01D02*
X157000Y879700D01*
G01X175725Y160280D02*
X224832Y111173D01*
G01X165162Y166241D02*
X213460Y117943D01*
G01X223256Y110604D02*
X174300Y159560D01*
G01X218422Y135879D02*
X197438Y156863D01*
G01D02*
Y196000D01*
G01X175725Y254374D02*
Y160280D01*
G01X215092Y133438D02*
X187299Y161231D01*
G01D02*
Y193609D01*
G01X183125Y194811D02*
Y161373D01*
G01D02*
X217036Y127462D01*
G01X185874Y269715D02*
Y160640D01*
G01D02*
X215336Y131178D01*
G01X216445Y126037D02*
X181700Y160782D01*
G01D02*
Y194220D01*
G01X165162Y255137D02*
Y166241D01*
G01X174300Y159560D02*
Y251644D01*
G01X197438Y196000D02*
X199693Y198255D01*
G01Y207045D02*
X197900Y208838D01*
G01D02*
Y302500D01*
G01X187299Y193609D02*
X187385Y193695D01*
G01D02*
Y268000D01*
G01X181100Y263481D02*
Y196836D01*
G01D02*
X183125Y194811D01*
G01X181700Y194220D02*
X179675Y196245D01*
G01D02*
Y262890D01*
G01X172824Y288764D02*
Y257275D01*
G01D02*
X175725Y254374D01*
G01X187385Y268000D02*
X189500Y270115D01*
G01D02*
Y290264D01*
G01X180362Y281263D02*
Y264219D01*
G01D02*
X181100Y263481D01*
G01X187438Y290310D02*
Y271279D01*
G01D02*
X185874Y269715D01*
G01X179675Y262890D02*
X176775Y265790D01*
G01D02*
Y286967D01*
G01X171100Y247500D02*
Y252828D01*
G01X174300Y251644D02*
X166687Y259257D01*
G01D02*
Y284643D01*
G01X197900Y302500D02*
X189500Y310900D01*
G01X178279Y329349D02*
Y294219D01*
G01D02*
X172824Y288764D01*
G01X189500Y290264D02*
X187385Y292379D01*
G01D02*
Y333132D01*
G01X184076Y336729D02*
Y284977D01*
G01D02*
X180362Y281263D01*
G01X185960Y340782D02*
Y291788D01*
G01D02*
X187438Y290310D01*
G01X176775Y286967D02*
X182546Y292738D01*
G01D02*
Y332075D01*
G01X167500Y302000D02*
X170105D01*
G01D02*
X172100Y303995D01*
G01D02*
Y314743D01*
G01X165500Y328769D02*
Y309310D01*
G01X166687Y284643D02*
X176854Y294810D01*
G01D02*
Y332347D01*
G01X189500Y310900D02*
Y322575D01*
G01D02*
X189365Y322710D01*
G01D02*
Y329905D01*
G01X179092Y351983D02*
Y330162D01*
G01D02*
X178279Y329349D01*
G01X197882Y344961D02*
X189920Y336999D01*
G01D02*
Y335667D01*
G01D02*
X188215Y333962D01*
G01X187385Y333132D02*
X188215Y333962D01*
G01X167687Y329434D02*
X169300Y331047D01*
G01D02*
Y339499D01*
G01D02*
X167423Y341376D01*
G01X170144Y344097D02*
X167423Y341376D01*
G01X182855Y349457D02*
Y337950D01*
G01D02*
X184076Y336729D01*
G01X187361Y342183D02*
X189309D01*
G01D02*
X195940Y348814D01*
G01X187361Y342183D02*
X185960Y340782D01*
G01X180617Y350289D02*
Y334004D01*
G01D02*
X181838Y332783D01*
G01X182546Y332075D02*
X181838Y332783D01*
G01X173277Y315920D02*
X174727Y317370D01*
G01D02*
Y320799D01*
G01D02*
X174943Y321015D01*
G01X172100Y314743D02*
X173277Y315920D01*
G01X176854Y344898D02*
Y332347D01*
G01X179381Y369903D02*
Y364281D01*
G01D02*
X178692Y363592D01*
G01D02*
Y352383D01*
G01D02*
X179092Y351983D01*
G01X196529Y352284D02*
X197882Y350931D01*
G01D02*
Y344961D01*
G01X170144Y388056D02*
Y344097D01*
G01X185970Y358962D02*
X185300Y358292D01*
G01D02*
Y351902D01*
G01D02*
X182855Y349457D01*
G01X182969Y352641D02*
X180617Y350289D01*
G01X176674Y344934D02*
Y345078D01*
G01D02*
X176854Y344898D01*
G01X171434Y398093D02*
X172027Y397500D01*
G01D02*
X237400D01*
G01X170217Y453618D02*
Y401117D01*
G01D02*
X166700Y397600D01*
G01D02*
Y391500D01*
G01D02*
X170144Y388056D01*
G01X182300Y414400D02*
Y411350D01*
G01X182550Y411600D02*
X182300Y411350D01*
G01X195000Y411600D02*
X200350D01*
G01X181400Y415300D02*
X182300Y414400D01*
G01X187600Y411600D02*
X182550D01*
G01X181328Y460701D02*
X181214Y460815D01*
G01D02*
X177935D01*
G01D02*
X177500Y461250D01*
G01X166100Y488192D02*
Y477934D01*
G01D02*
X174563Y469471D01*
G01D02*
Y464187D01*
G01D02*
X177500Y461250D01*
G01X166085Y457750D02*
X170217Y453618D01*
G01X185500Y461250D02*
X182393Y458143D01*
G01D02*
X177893D01*
G01D02*
X177500Y457750D01*
G01Y454300D02*
Y457750D01*
G01X169000Y463000D02*
Y465215D01*
G01D02*
X168563Y465652D01*
G01D02*
Y469995D01*
G01X169000Y458000D02*
X166862Y460138D01*
G01D02*
Y464838D01*
G01D02*
X167138Y465114D01*
G01D02*
Y469686D01*
G01X171000Y470558D02*
Y468000D01*
G01X167300Y486499D02*
Y478986D01*
G01D02*
X176079Y470207D01*
G01D02*
Y466921D01*
G01D02*
X177000Y466000D01*
G01X168231Y479399D02*
X176954Y470676D01*
G01D02*
Y470564D01*
G01D02*
X181518Y466000D01*
G01D02*
X182000D01*
G01X199333Y498696D02*
X179817D01*
G01D02*
X179002Y499511D01*
G01D02*
X177728D01*
G01D02*
X177262Y499045D01*
G01D02*
X176287D01*
G01D02*
X175215Y497973D01*
G01X165768Y488524D02*
X166100Y488192D01*
G01X175215Y510571D02*
X176744Y512100D01*
G01D02*
X177719D01*
G01D02*
X177728Y512109D01*
G01D02*
X179002D01*
G01D02*
X179011Y512100D01*
G01D02*
X186832D01*
G01D02*
X200232Y525500D01*
G01X167306Y492311D02*
Y491745D01*
G01D02*
X167336Y491715D01*
G01D02*
Y491425D01*
G01D02*
X168666Y490095D01*
G01D02*
X171136D01*
G01D02*
X171152Y490111D01*
G01D02*
X173652D01*
G01D02*
X175215Y491674D01*
G01X198000Y493500D02*
X204362D01*
G01X198000D02*
X193680Y497820D01*
G01D02*
X191483D01*
G01D02*
X180872Y497821D01*
G01D02*
X179454D01*
G01D02*
X179302Y497973D01*
G01D02*
X178365D01*
G01Y510571D02*
X187319D01*
G01D02*
X198248Y521500D01*
G01X165768Y491674D02*
Y490777D01*
G01D02*
X167900Y488645D01*
G01D02*
Y487099D01*
G01D02*
X167300Y486499D01*
G01X172065Y488524D02*
X168231Y484686D01*
G01D02*
Y479399D01*
G01X168599Y527221D02*
X170222Y525598D01*
G01D02*
X170300D01*
G01D02*
X171117Y524781D01*
G01D02*
X173677D01*
G01D02*
X175215Y526319D01*
G01X202200Y541000D02*
X190669Y529469D01*
G01D02*
X178365D01*
G01X198862Y547242D02*
X184238Y532618D01*
G01D02*
X178365D01*
G01X175215Y529469D02*
X176746Y531000D01*
G01D02*
X177721D01*
G01D02*
X177728Y531007D01*
G01D02*
X186407D01*
G01D02*
X199900Y544500D01*
G01X184500Y545250D02*
X185355Y544395D01*
G01D02*
Y537874D01*
G01D02*
X184787Y537306D01*
G01D02*
X177306D01*
G01D02*
X175767Y535767D01*
G01D02*
X175216D01*
G01X175215Y513721D02*
X176794Y515300D01*
G01D02*
X185700D01*
G01D02*
X201400Y531000D01*
G01X173000Y547500D02*
X170500Y545000D01*
G01D02*
Y541475D01*
G01D02*
X168916Y539891D01*
G01D02*
Y538916D01*
G01X178000Y547000D02*
X180638Y544362D01*
G01D02*
Y540638D01*
G01D02*
X179500Y539500D01*
G01D02*
X175797D01*
G01D02*
X175215Y538918D01*
G01X172065Y529469D02*
X173603Y531007D01*
G01D02*
Y536329D01*
G01D02*
X174654Y537380D01*
G01D02*
X175852D01*
G01D02*
X176972Y538500D01*
G01D02*
X180500D01*
G01D02*
X182000Y540000D01*
G01D02*
Y568815D01*
G01X173618Y516881D02*
Y518965D01*
G01D02*
X173603Y518980D01*
G01D02*
Y521558D01*
G01D02*
X175215Y523170D01*
G01X198248Y521500D02*
X205000D01*
G01X178365Y513721D02*
X186437D01*
G01D02*
X203216Y530500D01*
G01X201400Y536662D02*
X192595Y527857D01*
G01D02*
X174578D01*
G01D02*
X173040Y526319D01*
G01D02*
X172065D01*
G01X167000Y545500D02*
Y543847D01*
G01D02*
X167304Y543543D01*
G01D02*
Y540454D01*
G01D02*
X165766Y538916D01*
G01X178000Y542000D02*
X176456Y540456D01*
G01D02*
X174456D01*
G01D02*
X172918Y538918D01*
G01D02*
X172065D01*
G01X181811Y524978D02*
X180003Y523170D01*
G01D02*
X178365D01*
G01X169500Y547024D02*
Y542650D01*
G01D02*
X168916Y542066D01*
G01X173000Y542500D02*
X170527Y540027D01*
G01D02*
Y537377D01*
G01D02*
X168916Y535766D01*
G01X196782Y563564D02*
X198082Y564864D01*
G01D02*
X199009D01*
G01X184500Y548750D02*
Y564193D01*
G01D02*
X184189Y564504D01*
G01X182000Y568815D02*
X186416Y573231D01*
G01D02*
X191500Y578315D01*
G01D02*
Y581250D01*
G01X193600Y569800D02*
X194550Y570750D01*
G01D02*
X197500D01*
G01X197334Y567232D02*
X194968D01*
G01D02*
X193600Y568600D01*
G01D02*
Y569800D01*
G01X173000Y552500D02*
Y550524D01*
G01D02*
X169500Y547024D01*
G01X187371Y674413D02*
X189622Y672162D01*
G01D02*
X203597D01*
G01X239174Y651674D02*
X180826D01*
G01D02*
X176500Y656000D01*
G01X187918Y671850D02*
X189031Y670737D01*
G01D02*
X204188D01*
G01X187327Y670425D02*
X188440Y669312D01*
G01D02*
X204779D01*
G01X200827Y679875D02*
X185331D01*
G01D02*
X182481Y682725D01*
G01X200236Y681300D02*
X194652D01*
G01D02*
X191452Y684500D01*
G01X175200Y678500D02*
X175250Y678450D01*
G01D02*
X201418D01*
G01X202009Y677025D02*
X177972D01*
G01D02*
X177147Y676200D01*
G01D02*
X173400D01*
G01D02*
X171300Y678300D01*
G01X210352Y689852D02*
X198196D01*
G01D02*
X194585Y693463D01*
G01X167000Y686500D02*
X169688Y689188D01*
G01D02*
X192812D01*
G01D02*
X196425Y685575D01*
G01D02*
X198463D01*
G01D02*
X198465Y685577D01*
G01D02*
X217467D01*
G01X167129Y690613D02*
X193403D01*
G01D02*
X197014Y687002D01*
G01D02*
X217502D01*
G01X168444Y684150D02*
X172057Y687763D01*
G01D02*
X192221D01*
G01D02*
X195834Y684150D01*
G01D02*
X199054D01*
G01X191452Y684500D02*
X189000D01*
G01X216911Y688427D02*
X197605D01*
G01D02*
X193994Y692038D01*
G01D02*
X166506D01*
G01X199645Y682725D02*
X195243D01*
G01D02*
X191630Y686338D01*
G01D02*
X186838D01*
G01D02*
X185000Y684500D01*
G01X188335Y811500D02*
X212500D01*
G01X187204Y803000D02*
X207000D01*
G01X214000Y813500D02*
X189500D01*
G01D02*
X174265Y828735D01*
G01X187725Y809275D02*
X211225D01*
G01X215000Y816000D02*
X190500D01*
G01D02*
X169840Y836660D01*
G01X187220Y805000D02*
X208500D01*
G01X187236Y807000D02*
X210000D01*
G01X166000Y879200D02*
Y837000D01*
G01D02*
X174265Y828735D01*
G01X168500Y873700D02*
Y838000D01*
G01D02*
X169840Y836660D01*
G01X165748Y889470D02*
Y880964D01*
G01X168898Y889470D02*
Y882098D01*
G01D02*
X166000Y879200D01*
G01X172048Y889470D02*
Y877248D01*
G01D02*
X168500Y873700D01*
G01X224832Y108069D02*
X221607Y104844D01*
G01D02*
X221593D01*
G01D02*
X220516Y103767D01*
G01D02*
Y103753D01*
G01D02*
X219919Y103156D01*
G01D02*
Y97760D01*
G01D02*
X222252Y95427D01*
G01D02*
X233777D01*
G01X258861Y91751D02*
X230001D01*
G01D02*
X228163Y93589D01*
G01X257715Y88589D02*
X228163D01*
G01X260553Y85997D02*
X226195D01*
G01D02*
X218494Y93698D01*
G01D02*
Y104917D01*
G01D02*
X221373Y107796D01*
G01D02*
X222179D01*
G01D02*
X223256Y108873D01*
G01X235901Y126555D02*
X228596Y133860D01*
G01D02*
X225190D01*
G01D02*
X223171Y135879D01*
G01D02*
X218422D01*
G01X224832Y111173D02*
Y108069D01*
G01X222356Y133438D02*
X215092D01*
G01X217036Y127462D02*
X226456D01*
G01D02*
X227947Y128953D01*
G01D02*
X229471D01*
G01D02*
X234719Y123705D01*
G01X215336Y131178D02*
X229262D01*
G01D02*
X235310Y125130D01*
G01X224576Y116678D02*
Y120745D01*
G01D02*
X219284Y126037D01*
G01D02*
X216445D01*
G01X213460Y117943D02*
X213485D01*
G01D02*
X216758Y114670D01*
G01D02*
Y114645D01*
G01D02*
X221262Y110141D01*
G01D02*
Y109790D01*
G01D02*
X221418Y109634D01*
G01X223256Y108873D02*
Y110604D01*
G01X199693Y198255D02*
Y207045D01*
G01X200350Y411600D02*
X200500Y411750D01*
G01X202638Y434095D02*
Y431000D01*
G01D02*
X202469Y430831D01*
G01D02*
Y429873D01*
G01X207938Y433845D02*
X207688Y434095D01*
G01D02*
X202638D01*
G01X200500Y411750D02*
X203150D01*
G01D02*
X205100Y413700D01*
G01X220838Y431895D02*
Y428917D01*
G01D02*
X221699Y428056D01*
G01X215338Y433845D02*
X218888D01*
G01D02*
X220838Y431895D01*
G01X199880Y498149D02*
X202631Y500900D01*
G01D02*
X205200D01*
G01D02*
X206700Y499400D01*
G01D02*
Y498000D01*
G01X210000Y495744D02*
X208956D01*
G01D02*
X206700Y498000D01*
G01X199880Y498149D02*
X199333Y498696D01*
G01X204362Y493500D02*
X204862Y494000D01*
G01D02*
X206700D01*
G01X210000Y491744D02*
X208956D01*
G01D02*
X206700Y494000D01*
G01X217291Y524970D02*
X213780D01*
G01D02*
X213250Y525500D01*
G01X229000Y525750D02*
X225000D01*
G01D02*
X221000D01*
G01D02*
X220220Y524970D01*
G01D02*
X217291D01*
G01X213250Y530500D02*
X214762Y532012D01*
G01D02*
X262500D01*
G01X209750Y542500D02*
X208250Y541000D01*
G01D02*
X202200D01*
G01X200232Y525500D02*
X201900D01*
G01D02*
X209750D01*
G01X199900Y544500D02*
X201900Y546500D01*
G01X229000Y521750D02*
X232840D01*
G01X225000D02*
X221000D01*
G01X225000D02*
X229000D01*
G01X221000D02*
X218945D01*
G01D02*
X218707Y521988D01*
G01D02*
X216593D01*
G01D02*
X216355Y521750D01*
G01D02*
X213500D01*
G01D02*
X213250Y521500D01*
G01X201400Y531000D02*
Y532400D01*
G01D02*
X203500Y534500D01*
G01D02*
X209750D01*
G01X220600Y546500D02*
X219700Y547400D01*
G01X205000Y521500D02*
X209750D01*
G01X225000Y534750D02*
X232350D01*
G01D02*
X232600Y535000D01*
G01X225000Y534750D02*
X221000D01*
G01D02*
X217000D01*
G01D02*
X213500D01*
G01D02*
X213250Y534500D01*
G01X203216Y530500D02*
X206200D01*
G01D02*
X209750D01*
G01Y538500D02*
X207912Y536662D01*
G01D02*
X201400D01*
G01X222750Y558500D02*
X222800Y558550D01*
G01D02*
Y562100D01*
G01X218780Y560082D02*
X219031D01*
G01D02*
X221049Y562100D01*
G01D02*
X222800D01*
G01X199009Y564864D02*
X199559Y565414D01*
G01D02*
X199846D01*
G01D02*
X201429Y566997D01*
G01D02*
X201500Y567068D01*
G01D02*
Y570750D01*
G01X216241Y563095D02*
X215946Y562800D01*
G01D02*
X210510D01*
G01D02*
X200793D01*
G01D02*
X198862Y560869D01*
G01D02*
Y547242D01*
G01X201900Y546500D02*
X209750D01*
G01X226250Y558500D02*
X229800D01*
G01X222750Y550500D02*
X222700Y550450D01*
G01D02*
Y546500D01*
G01D02*
X220600D01*
G01X219700Y547400D02*
Y550500D01*
G01X234708D02*
X226250D01*
G01D02*
Y554500D01*
G01X209750Y550500D02*
X205300D01*
G01D02*
X203300Y548500D01*
G01X205961Y666462D02*
X207974Y668475D01*
G01D02*
X208011D01*
G01D02*
X208013Y668477D01*
G01D02*
X210375D01*
G01D02*
X210376Y668476D01*
G01D02*
X211556D01*
G01D02*
X211557Y668475D01*
G01D02*
X313110D01*
G01X203597Y672162D02*
X205610Y674175D01*
G01D02*
X205647D01*
G01D02*
X205649Y674177D01*
G01D02*
X212739D01*
G01D02*
X212740Y674176D01*
G01D02*
X213920D01*
G01D02*
X213921Y674175D01*
G01D02*
X297315D01*
G01X312519Y669900D02*
X212148D01*
G01D02*
X212147Y669901D01*
G01D02*
X210967D01*
G01D02*
X210966Y669902D01*
G01D02*
X207422D01*
G01D02*
X207420Y669900D01*
G01D02*
X207383D01*
G01D02*
X205370Y667887D01*
G01X204188Y670737D02*
X206201Y672750D01*
G01D02*
X206238D01*
G01D02*
X206240Y672752D01*
G01D02*
X212148D01*
G01D02*
X212149Y672751D01*
G01D02*
X213329D01*
G01D02*
X213330Y672750D01*
G01D02*
X311337D01*
G01X313701Y667050D02*
X210966D01*
G01D02*
X210965Y667051D01*
G01D02*
X209785D01*
G01D02*
X209784Y667052D01*
G01D02*
X208604D01*
G01D02*
X208602Y667050D01*
G01D02*
X208565D01*
G01D02*
X206552Y665037D01*
G01X204779Y669312D02*
X206792Y671325D01*
G01D02*
X206829D01*
G01D02*
X206831Y671327D01*
G01D02*
X211557D01*
G01D02*
X211558Y671326D01*
G01D02*
X212738D01*
G01D02*
X212739Y671325D01*
G01D02*
X311928D01*
G01X207143Y663612D02*
X209156Y665625D01*
G01D02*
X209193D01*
G01D02*
X209194Y665626D01*
G01D02*
X210374D01*
G01D02*
X210375Y665625D01*
G01D02*
X833375D01*
G01X294923Y679875D02*
X216285D01*
G01D02*
X216284Y679876D01*
G01D02*
X215104D01*
G01D02*
X215103Y679877D01*
G01D02*
X200829D01*
G01D02*
X200827Y679875D01*
G01X294332Y681300D02*
X216876D01*
G01D02*
X216875Y681301D01*
G01D02*
X215695D01*
G01D02*
X215694Y681302D01*
G01D02*
X200238D01*
G01D02*
X200236Y681300D01*
G01X201000Y674000D02*
X202602Y675602D01*
G01D02*
X213330D01*
G01D02*
X213331Y675601D01*
G01D02*
X214511D01*
G01D02*
X214512Y675600D01*
G01D02*
X296710D01*
G01X201418Y678450D02*
X201420Y678452D01*
G01D02*
X214512D01*
G01D02*
X214513Y678451D01*
G01D02*
X215693D01*
G01D02*
X215694Y678450D01*
G01D02*
X295514D01*
G01X207734Y662187D02*
X209747Y664200D01*
G01D02*
X209784D01*
G01D02*
X289605Y664199D01*
G01X296105Y677025D02*
X215103D01*
G01D02*
X215102Y677026D01*
G01D02*
X213922D01*
G01D02*
X213921Y677027D01*
G01D02*
X202011D01*
G01D02*
X202009Y677025D01*
G01X206952Y655370D02*
X207122Y655200D01*
G01D02*
X216795D01*
G01D02*
X219520Y657925D01*
G01D02*
X826979D01*
G01X208325Y660762D02*
X209763Y662200D01*
G01D02*
X828752D01*
G01X827570Y659350D02*
X210945D01*
G01D02*
X209507Y657912D01*
G01X208916Y659337D02*
X210354Y660775D01*
G01D02*
X828161D01*
G01X235575Y703075D02*
X231500Y699000D01*
G01X220225Y789775D02*
Y699725D01*
G01D02*
X210352Y689852D01*
G01X217467Y685577D02*
X217468Y685576D01*
G01D02*
X218648D01*
G01D02*
X218649Y685575D01*
G01D02*
X221075D01*
G01D02*
X237000Y701500D01*
G01X217502Y687002D02*
X224500Y694000D01*
G01D02*
Y796000D01*
G01X219000Y694000D02*
X221650Y696650D01*
G01D02*
Y791850D01*
G01X199054Y684150D02*
X199056Y684152D01*
G01D02*
X216876D01*
G01D02*
X216877Y684151D01*
G01D02*
X218057D01*
G01D02*
X218058Y684150D01*
G01D02*
X293150D01*
G01X223075Y793925D02*
Y694591D01*
G01D02*
X216911Y688427D01*
G01X293741Y682725D02*
X217467D01*
G01D02*
X217466Y682726D01*
G01D02*
X216286D01*
G01D02*
X216285Y682727D01*
G01D02*
X199647D01*
G01D02*
X199645Y682725D01*
G01X212500Y811500D02*
X235575Y788425D01*
G01X207000Y803000D02*
X218937Y791063D01*
G01D02*
X220225Y789775D01*
G01X237000Y790500D02*
X214000Y813500D01*
G01X211225Y809275D02*
X212841Y807659D01*
G01X224500Y796000D02*
X212841Y807659D01*
G01X238500Y792500D02*
X215000Y816000D01*
G01X221650Y791850D02*
X217104Y796396D01*
G01X208500Y805000D02*
X217104Y796396D01*
G01X210000Y807000D02*
X214649Y802351D01*
G01D02*
X223075Y793925D01*
G01X258100Y93589D02*
X248692D01*
G01D02*
X243831Y98450D01*
G01D02*
X236800D01*
G01X233777Y95427D02*
X236800Y98450D01*
G01X260719Y111505D02*
Y93609D01*
G01D02*
X258861Y91751D01*
G01X262513Y112675D02*
Y93387D01*
G01D02*
X257715Y88589D01*
G01X260562Y85988D02*
X260553Y85997D01*
G01X257422Y121792D02*
X252659Y126555D01*
G01D02*
X235901D01*
G01X234719Y123705D02*
X248519D01*
G01D02*
X260719Y111505D01*
G01X235310Y125130D02*
X250058D01*
G01D02*
X262513Y112675D01*
G01X237400Y397500D02*
X239100Y399200D01*
G01X243650Y473600D02*
X247661D01*
G01X243400Y468300D02*
Y473350D01*
G01D02*
X243650Y473600D01*
G01X247473Y455600D02*
X243650D01*
G01X243400Y460900D02*
Y455850D01*
G01D02*
X243650Y455600D01*
G01X289838Y532012D02*
X262500D01*
G01X232840Y521750D02*
X233701Y522611D01*
G01X234777Y550569D02*
X234708Y550500D01*
G01X257110Y654750D02*
X271500Y640360D01*
G01X241521Y654021D02*
X242250Y654750D01*
G01D02*
X257110D01*
G01X241521Y654021D02*
X239174Y651674D01*
G01X235575Y788425D02*
Y703075D01*
G01X237000Y701500D02*
Y790500D01*
G01X244337Y880069D02*
Y707163D01*
G01D02*
X249797Y701703D01*
G01X300587Y700212D02*
X251288D01*
G01D02*
X249797Y701703D01*
G01X245762Y879478D02*
Y711238D01*
G01D02*
X248890Y708110D01*
G01X298012Y701637D02*
X255363D01*
G01D02*
X248890Y708110D01*
G01X241000Y712500D02*
X238500Y715000D01*
G01D02*
Y792500D01*
G01X250500Y716000D02*
X254212Y712288D01*
G01X307167Y707869D02*
X258631D01*
G01D02*
X254212Y712288D01*
G01X257728Y722272D02*
X266575Y713425D01*
G01X259633Y715867D02*
X263500Y712000D01*
G01D02*
X307068D01*
G01X252500Y718500D02*
X260816Y710184D01*
G01D02*
X261706Y709294D01*
G01D02*
X307758D01*
G01X247187Y878887D02*
Y714813D01*
G01D02*
X255968Y706032D01*
G01X295468Y703062D02*
X258938D01*
G01D02*
X255968Y706032D01*
G01X276837Y730462D02*
X262462D01*
G01D02*
X258100Y726100D01*
G01X263500Y748700D02*
X263950D01*
G01D02*
X267500Y752250D01*
G01X263000Y749200D02*
X263500Y748700D01*
G01X250500Y754500D02*
Y716000D01*
G01X263000Y755750D02*
X255350Y748100D01*
G01D02*
Y724650D01*
G01D02*
X257728Y722272D01*
G01X253925Y752909D02*
Y721575D01*
G01D02*
X259633Y715867D01*
G01X252500Y753500D02*
Y718500D01*
G01X263000Y752250D02*
Y749200D01*
G01X281681Y764851D02*
X260851D01*
G01D02*
X250500Y754500D01*
G01X280500Y762000D02*
X263016D01*
G01D02*
X253925Y752909D01*
G01X281091Y763425D02*
X262425D01*
G01D02*
X252500Y753500D01*
G01X244488Y889470D02*
Y880220D01*
G01D02*
X244337Y880069D01*
G01X247638Y889470D02*
Y881354D01*
G01D02*
X245762Y879478D01*
G01X250788Y889470D02*
Y882488D01*
G01D02*
X247187Y878887D01*
G01X289300Y364210D02*
Y335353D01*
G01D02*
X307425Y317228D01*
G01X288270Y365240D02*
X289300Y364210D01*
G01X298300Y431600D02*
Y381223D01*
G01D02*
X308637Y370886D01*
G01X300300Y408600D02*
X299725Y408025D01*
G01D02*
Y381814D01*
G01D02*
X316669Y364870D01*
G01X293800Y436100D02*
X298300Y431600D01*
G01X293776Y456788D02*
Y441324D01*
G01D02*
X300300Y434800D01*
G01X301900Y436100D02*
X295202Y442798D01*
G01D02*
Y465983D01*
G01X298564Y480896D02*
Y471361D01*
G01D02*
X293777Y466574D01*
G01D02*
X293776Y456788D01*
G01X295202Y465983D02*
X299989Y470770D01*
G01X299653Y515015D02*
Y481985D01*
G01D02*
X298564Y480896D01*
G01X299989Y480305D02*
X301078Y481394D01*
G01X306900Y529100D02*
X292750D01*
G01D02*
X289838Y532012D01*
G01X295876Y520800D02*
Y518790D01*
G01D02*
X297423Y517243D01*
G01D02*
X297425D01*
G01D02*
X299653Y515015D01*
G01X290000Y578165D02*
X285700D01*
G01X294250Y578500D02*
X290335D01*
G01D02*
X290000Y578165D01*
G01X289835Y583165D02*
X285900D01*
G01X294250Y583000D02*
X290000D01*
G01D02*
X289835Y583165D01*
G01Y588165D02*
X285613D01*
G01D02*
X285606Y588172D01*
G01X294250Y588500D02*
X290170D01*
G01D02*
X289835Y588165D01*
G01X271500Y640360D02*
Y639500D01*
G01X297315Y674175D02*
X326000Y702860D01*
G01X312855Y697807D02*
X294923Y679875D01*
G01X311430Y698398D02*
X294332Y681300D01*
G01X296710Y675600D02*
X324574Y703464D01*
G01X295514Y678450D02*
X314280Y697216D01*
G01X289605Y664199D02*
X290785D01*
G01D02*
X290786Y664198D01*
G01D02*
X301422D01*
G01X315705Y696625D02*
X296105Y677025D01*
G01X302406Y706031D02*
X298012Y701637D01*
G01X293150Y684150D02*
X308580Y699580D01*
G01X266575Y713425D02*
X307659D01*
G01X310005Y698989D02*
X293741Y682725D01*
G01X298406Y706000D02*
X295468Y703062D01*
G01X278406Y723148D02*
Y724089D01*
G01D02*
X275609Y726886D01*
G01D02*
X275050Y727445D01*
G01D02*
X272137D01*
G01D02*
X270430Y725738D01*
G01X278050Y733267D02*
Y731675D01*
G01D02*
X276837Y730462D01*
G01X295678Y732681D02*
X293681D01*
G01D02*
X290778Y729778D01*
G01D02*
Y726472D01*
G01D02*
X290799Y726451D01*
G01D02*
Y726333D01*
G01D02*
X290720D01*
G01X294506Y723148D02*
Y724545D01*
G01D02*
X296132Y726171D01*
G01X290500Y723250D02*
X294404D01*
G01D02*
X294506Y723148D01*
G01X293738Y729123D02*
Y728565D01*
G01D02*
X296132Y726171D01*
G01X300488Y750431D02*
X298812Y748755D01*
G01D02*
Y740093D01*
G01D02*
X301738Y737167D01*
G01Y734510D02*
X297192Y729964D01*
G01D02*
X294579D01*
G01D02*
X293738Y729123D01*
G01X286406Y723148D02*
X287278Y724020D01*
G01D02*
Y729031D01*
G01D02*
X285217D01*
G01D02*
X284038Y727852D01*
G01D02*
X280271D01*
G01D02*
X279045Y729078D01*
G01X282406Y723148D02*
Y723314D01*
G01D02*
X285333Y726241D01*
G01X274406Y723148D02*
X273387D01*
G01D02*
X269056Y718817D01*
G01D02*
X267011D01*
G01X266980Y723854D02*
Y718848D01*
G01D02*
X267011Y718817D01*
G01X278050Y736767D02*
X280762D01*
G01D02*
X283004Y739009D01*
G01X278282Y743219D02*
X281281D01*
G01D02*
X283196Y741304D01*
G01D02*
Y739009D01*
G01D02*
X283004D01*
G01X298554Y723163D02*
Y728530D01*
G01D02*
X298620Y728596D01*
G01D02*
X300524Y730500D01*
G01X295678Y736181D02*
X297192D01*
G01D02*
X297373Y736000D01*
G01D02*
X299500D01*
G01X295560Y743250D02*
Y739272D01*
G01D02*
X295678Y739154D01*
G01D02*
Y736181D01*
G01X289678Y756681D02*
X289359Y757000D01*
G01D02*
X285000D01*
G01X290440Y749750D02*
Y754238D01*
G01D02*
X289678Y755000D01*
G01D02*
Y756681D01*
G01X285000Y752250D02*
Y757000D01*
G01X279500Y756250D02*
X276199D01*
G01D02*
X275900Y755951D01*
G01X275722Y749719D02*
Y755773D01*
G01D02*
X275900Y755951D01*
G01X293000Y749750D02*
Y752500D01*
G01D02*
X294000Y753500D01*
G01D02*
X297000D01*
G01D02*
X297500Y754000D01*
G01D02*
Y757000D01*
G01X293678Y756681D02*
X293997Y757000D01*
G01D02*
X297500D01*
G01X286906Y768648D02*
Y765903D01*
G01D02*
X287115Y765694D01*
G01D02*
Y765584D01*
G01X279500Y759750D02*
X281500Y757750D01*
G01D02*
Y752000D01*
G01X293678Y760181D02*
X294209Y760712D01*
G01D02*
X299500D01*
G01D02*
X300488Y759724D01*
G01X267500Y752250D02*
X269250D01*
G01D02*
X271781Y749719D01*
G01D02*
X273162D01*
G01X306596Y763562D02*
X297939D01*
G01D02*
X297808Y763693D01*
G01D02*
X282839D01*
G01D02*
X281681Y764851D01*
G01X283500Y765631D02*
X282855Y766276D01*
G01D02*
X279724D01*
G01D02*
X278500Y767500D01*
G01D02*
Y768500D01*
G01X282378Y768681D02*
X278681D01*
G01D02*
X278500Y768500D01*
G01X289678Y760181D02*
X282319D01*
G01D02*
X280500Y762000D01*
G01X300790Y762137D02*
X297348D01*
G01D02*
X297217Y762268D01*
G01D02*
X282248D01*
G01D02*
X281091Y763425D01*
G01X295079Y768600D02*
X294924Y768755D01*
G01D02*
X290830D01*
G01X293692Y765571D02*
X293690D01*
G01D02*
Y765559D01*
G01D02*
X293631Y765500D01*
G01D02*
X291700D01*
G01D02*
X290830Y766370D01*
G01D02*
Y768755D01*
G01X299164Y768841D02*
Y765711D01*
G01D02*
X299184Y765691D01*
G01X307425Y317228D02*
Y309838D01*
G01X308637Y370886D02*
Y320196D01*
G01D02*
X310485Y318348D01*
G01D02*
Y314670D01*
G01X340750Y331900D02*
X321454Y351196D01*
G01X316669Y364870D02*
Y355981D01*
G01D02*
X321454Y351196D01*
G01X359061Y336478D02*
X330942Y364597D01*
G01D02*
Y377058D01*
G01D02*
X301900Y406100D01*
G01X343259Y386557D02*
X317731Y412085D01*
G01X307700Y454800D02*
Y410610D01*
G01D02*
X336498Y381812D01*
G01X344684Y387148D02*
X319156Y412676D01*
G01X300300Y434800D02*
Y408600D01*
G01X363270Y380738D02*
X327706Y416302D01*
G01X355872Y382088D02*
X323431Y414529D01*
G01X301900Y406100D02*
Y436100D01*
G01X346109Y387739D02*
X320581Y413267D01*
G01X358362Y381614D02*
X324856Y415120D01*
G01X360820Y381172D02*
X326281Y415711D01*
G01X347534Y388330D02*
X322006Y413858D01*
G01X317731Y412085D02*
Y425172D01*
G01D02*
X313300Y429603D01*
G01X319156Y412676D02*
Y428144D01*
G01D02*
X313294Y434006D01*
G01X370700Y375844D02*
X330556Y415988D01*
G01D02*
Y465772D01*
G01X393975Y354585D02*
X331981Y416579D01*
G01D02*
Y466363D01*
G01X327706Y416302D02*
Y464590D01*
G01X395400Y355176D02*
X333406Y417170D01*
G01D02*
Y467630D01*
G01X323431Y414529D02*
Y458269D01*
G01X320581Y413267D02*
Y430319D01*
G01D02*
X313500Y437400D01*
G01X324856Y415120D02*
Y460378D01*
G01X326281Y415711D02*
Y462578D01*
G01X322006Y413858D02*
Y432494D01*
G01D02*
X313500Y441000D01*
G01X330000Y496213D02*
Y477700D01*
G01D02*
X334831Y472869D01*
G01X301602Y479902D02*
Y466198D01*
G01D02*
X303700Y464100D01*
G01D02*
Y458800D01*
G01D02*
X307700Y454800D01*
G01X330556Y465772D02*
X325751Y470577D01*
G01D02*
Y507851D01*
G01X331981Y466363D02*
X327176Y471168D01*
G01D02*
Y503887D01*
G01X336256Y473460D02*
X333102Y476614D01*
G01D02*
Y485902D01*
G01X327706Y464590D02*
X322305Y469991D01*
G01X333406Y467630D02*
X329014Y472022D01*
G01X323431Y458269D02*
X321900Y459800D01*
G01X299989Y470770D02*
Y480305D01*
G01X324856Y460378D02*
X322036Y463198D01*
G01X326281Y462578D02*
X322268Y466591D01*
G01X330000Y496213D02*
Y501900D01*
G01X304400Y511400D02*
X305638Y510162D01*
G01D02*
Y490539D01*
G01D02*
X302503Y487404D01*
G01D02*
Y480803D01*
G01D02*
X301602Y479902D01*
G01X325751Y507851D02*
X327512Y509612D01*
G01X327176Y503887D02*
X327589Y504300D01*
G01X301078Y481394D02*
Y502378D01*
G01D02*
X303800Y505100D01*
G01X313110Y668475D02*
X342773Y698138D01*
G01X342182Y699563D02*
X312519Y669900D01*
G01X311337Y672750D02*
X341000Y702413D01*
G01X335976Y689325D02*
X313701Y667050D01*
G01X311928Y671325D02*
X341591Y700988D01*
G01X301422Y664198D02*
X301424Y664200D01*
G01D02*
X830300D01*
G01X334918Y714918D02*
X328331Y708331D01*
G01X326000Y702860D02*
Y706000D01*
G01D02*
X328331Y708331D01*
G01X306406Y706031D02*
X300587Y700212D01*
G01X308580Y699580D02*
Y706420D01*
G01D02*
X308244Y706756D01*
G01D02*
Y706792D01*
G01D02*
X307167Y707869D01*
G01X307659Y713425D02*
X312855Y708229D01*
G01D02*
Y697807D01*
G01X307068Y712000D02*
X311430Y707638D01*
G01D02*
Y698398D01*
G01X324574Y703464D02*
Y709074D01*
G01D02*
X329913Y714413D01*
G01X331843Y716343D02*
X329913Y714413D01*
G01X314280Y697216D02*
Y697218D01*
G01D02*
X318000Y700938D01*
G01D02*
Y709048D01*
G01D02*
X328145Y719193D01*
G01X307758Y709294D02*
X310005Y707047D01*
G01D02*
Y698989D01*
G01X328736Y717768D02*
X321500Y710532D01*
G01D02*
Y706500D01*
G01D02*
Y702422D01*
G01D02*
X315705Y696627D01*
G01D02*
Y696625D01*
G01X301310Y726403D02*
X301490Y726583D01*
G01D02*
X303614D01*
G01D02*
X306471Y723726D01*
G01D02*
Y722269D01*
G01X302554Y723163D02*
X303448Y722269D01*
G01D02*
X306471D01*
G01X327678Y732681D02*
Y731178D01*
G01D02*
X326000Y729500D01*
G01D02*
Y729000D01*
G01X337581Y732681D02*
X327678D01*
G01X301000Y747750D02*
X304440D01*
G01D02*
X306440Y749750D01*
G01X301738Y737167D02*
Y734510D01*
G01X327560Y743250D02*
X330250D01*
G01D02*
X332500Y741000D01*
G01D02*
Y739500D01*
G01X327678Y736181D02*
X329181D01*
G01D02*
X332500Y739500D01*
G01X317000Y748250D02*
Y750043D01*
G01X311678Y732681D02*
X313157Y731202D01*
G01D02*
Y728613D01*
G01D02*
X310742Y726198D01*
G01D02*
X307278D01*
G01X311678Y736181D02*
X313052Y734807D01*
G01D02*
X315531D01*
G01X311560Y743250D02*
Y736299D01*
G01D02*
X311678Y736181D01*
G01X383327Y716343D02*
X331843D01*
G01X328145Y719193D02*
X382145D01*
G01X310406Y723148D02*
Y723499D01*
G01D02*
X313408Y726501D01*
G01D02*
X314436D01*
G01D02*
X315132Y727197D01*
G01D02*
X315410D01*
G01D02*
X318162Y729949D01*
G01X314812Y752617D02*
Y738692D01*
G01D02*
X319156Y734348D01*
G01D02*
Y730943D01*
G01D02*
X318162Y729949D01*
G01X300524Y730500D02*
X302000D01*
G01X382736Y717768D02*
X328736D01*
G01X303000Y756500D02*
Y755940D01*
G01D02*
X306440Y752500D01*
G01D02*
Y749750D01*
G01X307178Y756681D02*
X303181D01*
G01D02*
X303000Y756500D01*
G01X311178Y756681D02*
X311897Y757400D01*
G01D02*
X315100D01*
G01X309000Y749750D02*
Y754503D01*
G01D02*
X311178Y756681D01*
G01X300488Y759724D02*
Y750431D01*
G01X362533Y808033D02*
X331380Y776880D01*
G01D02*
X319685D01*
G01D02*
X316167Y773362D01*
G01D02*
X313242D01*
G01D02*
X311406Y775198D01*
G01X303406Y768648D02*
Y766106D01*
G01D02*
X302700Y765400D01*
G01X325678Y760181D02*
X322359Y763500D01*
G01D02*
X309638D01*
G01D02*
X307400Y765738D01*
G01X302700Y765400D02*
X307062D01*
G01D02*
X307400Y765738D01*
G01X307500Y780100D02*
X309400Y778200D01*
G01D02*
Y774605D01*
G01D02*
X312068Y771937D01*
G01D02*
X316758D01*
G01D02*
X319742Y774921D01*
G01D02*
X335921D01*
G01X307406Y775198D02*
X307500Y775292D01*
G01D02*
Y780100D01*
G01X321678Y756681D02*
X321040D01*
G01D02*
X317453Y753094D01*
G01D02*
Y752192D01*
G01X322440Y749750D02*
Y755919D01*
G01D02*
X321678Y756681D01*
G01X317000Y750043D02*
X317453Y750496D01*
G01D02*
Y752192D01*
G01X315406Y775200D02*
X319815Y779609D01*
G01D02*
X328609D01*
G01D02*
X364759Y815759D01*
G01X321678Y760181D02*
X319890Y761969D01*
G01D02*
X317084D01*
G01D02*
X317052Y761937D01*
G01D02*
X314348D01*
G01D02*
X314316Y761969D01*
G01D02*
X308189D01*
G01D02*
X306596Y763562D01*
G01X325678Y756681D02*
X327227Y758230D01*
G01D02*
X329575D01*
G01X325000Y749750D02*
Y756003D01*
G01D02*
X325678Y756681D01*
G01X319406Y767648D02*
X313348D01*
G01D02*
X311200Y765500D01*
G01X311178Y760181D02*
X315484D01*
G01D02*
X317338Y758327D01*
G01D02*
Y756473D01*
G01D02*
X315959Y755094D01*
G01D02*
Y753863D01*
G01D02*
X315290Y753194D01*
G01D02*
Y753095D01*
G01D02*
X314812Y752617D01*
G01X307178Y760181D02*
X307171Y760188D01*
G01D02*
X302739D01*
G01D02*
X300790Y762137D01*
G01X315406Y765598D02*
X315808Y766000D01*
G01D02*
X317861D01*
G01D02*
X318001Y765860D01*
G01D02*
X321860D01*
G01D02*
X322795Y764925D01*
G01D02*
X322950D01*
G01D02*
X323875Y764000D01*
G01D02*
X326405D01*
G01D02*
X327373Y764968D01*
G01D02*
Y765761D01*
G01X323406Y767648D02*
X326481D01*
G01D02*
X327373Y766756D01*
G01D02*
Y765761D01*
G01X393601Y168200D02*
X364132Y197669D01*
G01D02*
Y318068D01*
G01D02*
X350300Y331900D01*
G01D02*
X340750D01*
G01X359061Y335014D02*
Y336478D01*
G01Y335014D02*
X374400Y319675D01*
G01X352003Y358603D02*
X343259Y367347D01*
G01D02*
Y386557D01*
G01X336498Y381812D02*
Y366049D01*
G01D02*
X357847Y344700D01*
G01D02*
X375290D01*
G01X354505Y356102D02*
Y358700D01*
G01D02*
X344684Y368521D01*
G01D02*
Y387148D01*
G01X363270Y356940D02*
Y380738D01*
G01X355872Y363965D02*
Y382088D01*
G01X356953Y353653D02*
Y358268D01*
G01D02*
X346109Y369112D01*
G01D02*
Y387739D01*
G01X358362Y361649D02*
Y381614D01*
G01X360820Y359299D02*
Y381172D01*
G01X359403Y351203D02*
Y357834D01*
G01D02*
X347534Y369703D01*
G01D02*
Y388330D01*
G01X334831Y417761D02*
X396825Y355767D01*
G01X399793Y356831D02*
X338725Y417899D01*
G01X398368Y356240D02*
X336256Y418352D01*
G01X334831Y472869D02*
Y417761D01*
G01X338725Y417899D02*
Y481514D01*
G01X336256Y418352D02*
Y473460D01*
G01X338725Y481514D02*
Y488305D01*
G01D02*
X335570Y491460D01*
G01X363500Y704000D02*
X365350Y702150D01*
G01D02*
X437458D01*
G01X342773Y698138D02*
X355098D01*
G01D02*
X359636Y693600D01*
G01D02*
X360320D01*
G01D02*
X360321Y693599D01*
G01D02*
X374545D01*
G01X383918Y714918D02*
X334918D01*
G01X344200Y696300D02*
X347550Y692950D01*
G01D02*
X355334D01*
G01D02*
X357535Y690749D01*
G01D02*
X375727D01*
G01X465625Y695025D02*
X360227D01*
G01D02*
X355689Y699563D01*
G01D02*
X342182D01*
G01X341000Y702413D02*
X356871D01*
G01D02*
X361409Y697875D01*
G01D02*
X464443D01*
G01X468272Y689324D02*
X356944D01*
G01D02*
X356943Y689325D01*
G01D02*
X335976D01*
G01X341591Y700988D02*
X356280D01*
G01D02*
X360818Y696450D01*
G01D02*
X465034D01*
G01X334800Y712000D02*
X336293Y713493D01*
G01D02*
X384509D01*
G01X367000Y704000D02*
X368838D01*
G01X360000D02*
X363275Y700725D01*
G01D02*
X440100D01*
G01X375136Y692174D02*
X358126D01*
G01D02*
X354300Y696000D01*
G01X453274Y699300D02*
X362000D01*
G01D02*
X356800Y704500D01*
G01D02*
X354300D01*
G01X417988Y813088D02*
X337581Y732681D01*
G01X335921Y774921D02*
X360807Y799807D01*
G01X372346Y817846D02*
X362533Y808033D01*
G01X373771Y812771D02*
X360807Y799807D01*
G01X370921Y821921D02*
X364759Y815759D01*
G01X367323Y889470D02*
Y876477D01*
G01D02*
X370921Y872879D01*
G01X437510Y131800D02*
X401110Y168200D01*
G01D02*
X393601D01*
G01X370125Y198722D02*
X395822Y173025D01*
G01D02*
X403111D01*
G01X375637Y234463D02*
Y200037D01*
G01D02*
X397824Y177850D01*
G01D02*
X405112D01*
G01X407113Y182675D02*
X399829D01*
G01D02*
X381101Y201403D01*
G01D02*
Y233101D01*
G01X400400Y189100D02*
X404217Y192917D01*
G01X407704Y184100D02*
X400862D01*
G01D02*
X383600Y201362D01*
G01D02*
Y203200D01*
G01X370125Y237425D02*
Y198722D01*
G01X396825Y245835D02*
X405642Y237018D01*
G01X389150Y247976D02*
X375637Y234463D01*
G01X381101Y233101D02*
X393975Y245975D01*
G01X404217Y236427D02*
X395400Y245244D01*
G01X374400Y319675D02*
Y241700D01*
G01D02*
X370125Y237425D01*
G01X396825Y355767D02*
Y245835D01*
G01X389150Y330840D02*
Y247976D01*
G01X393975Y245975D02*
Y354585D01*
G01X408492Y238200D02*
X399792Y246900D01*
G01D02*
Y320920D01*
G01X407067Y237609D02*
X398367Y246309D01*
G01D02*
Y321467D01*
G01X395400Y245244D02*
Y355176D01*
G01X375290Y344700D02*
X389150Y330840D01*
G01X399792Y320920D02*
X399793Y320921D01*
G01D02*
Y356831D01*
G01X398367Y321467D02*
X398368Y321468D01*
G01D02*
Y356240D01*
G01X370700Y353900D02*
Y375844D01*
G01X374545Y693599D02*
X374546Y693600D01*
G01D02*
X466500D01*
G01X480750Y811750D02*
X383918Y714918D01*
G01X370500Y705500D02*
X371000Y705000D01*
G01D02*
X432308D01*
G01X375727Y690749D02*
X375728Y690750D01*
G01D02*
X467682D01*
G01X384509Y713493D02*
X456854Y785838D01*
G01X368838Y704000D02*
X369263Y703575D01*
G01D02*
X434950D01*
G01X467091Y692175D02*
X375137D01*
G01D02*
X375136Y692174D01*
G01X481134Y814150D02*
X383327Y716343D01*
G01X382145Y719193D02*
X480952Y818000D01*
G01X480543Y815575D02*
X382736Y717768D01*
G01X373771Y874061D02*
Y812771D01*
G01X372346Y873470D02*
Y817846D01*
G01X370921Y872879D02*
Y821921D01*
G01X370473Y889470D02*
Y880673D01*
G01D02*
X368500Y878700D01*
G01D02*
Y877316D01*
G01D02*
X372346Y873470D01*
G01X373622Y889470D02*
Y874210D01*
G01D02*
X373771Y874061D01*
G01X403111Y173025D02*
X439074Y137062D01*
G01X405112Y177850D02*
X438824Y144138D01*
G01X459348Y155475D02*
X434313D01*
G01D02*
X407113Y182675D01*
G01X433000Y169700D02*
X408492Y194208D01*
G01X459186Y156901D02*
X434904D01*
G01D02*
X407704Y184100D01*
G01X405642Y237018D02*
Y192098D01*
G01D02*
X411400Y186340D01*
G01D02*
Y183900D01*
G01X408492Y194208D02*
Y238200D01*
G01X421757Y177999D02*
X407067Y192689D01*
G01D02*
Y237609D01*
G01X404217Y192917D02*
Y236427D01*
G01X432308Y705000D02*
X487949Y760641D01*
G01X434950Y703575D02*
X495307Y763932D01*
G01X431100Y826200D02*
X417988Y813088D01*
G01X431100Y865600D02*
Y826200D01*
G01X427166Y889470D02*
Y869534D01*
G01D02*
X431100Y865600D01*
G01X481800Y134448D02*
X464378D01*
G01D02*
X461730Y131800D01*
G01D02*
X437510D01*
G01X439074Y137062D02*
X460044D01*
G01D02*
X462257Y139275D01*
G01D02*
X479801D01*
G01X438824Y144138D02*
X477838D01*
G01X478150Y152135D02*
X462688D01*
G01D02*
X459348Y155475D01*
G01X477559Y153560D02*
X463279D01*
G01D02*
X459939Y156900D01*
G01D02*
X459187D01*
G01D02*
X459186Y156901D01*
G01X465485Y190680D02*
X453600Y202565D01*
G01D02*
Y245705D01*
G01D02*
X478607Y270712D01*
G01X437458Y702150D02*
X487744Y752436D01*
G01X466500Y693600D02*
X514900Y742000D01*
G01X467682Y690750D02*
X505432Y728500D01*
G01X514226Y743626D02*
X465625Y695025D01*
G01X464443Y697875D02*
X514943Y748375D01*
G01X504948Y726000D02*
X468272Y689324D01*
G01X465034Y696450D02*
X515533Y746949D01*
G01X440100Y700725D02*
X495824Y756449D01*
G01X506416Y731500D02*
X467091Y692175D01*
G01X509474Y755500D02*
X453274Y699300D01*
G01X456854Y785838D02*
X478837D01*
G01X491850Y144498D02*
X481800Y134448D01*
G01X479801Y139275D02*
X490426Y149900D01*
G01X480910Y164099D02*
Y174875D01*
G01D02*
X480032Y175753D01*
G01X477838Y144138D02*
X488425Y154725D01*
G01D02*
X526125D01*
G01X494400Y176300D02*
X498900Y171800D01*
G01X522750Y159550D02*
X485565D01*
G01D02*
X478150Y152135D01*
G01X520726Y145075D02*
X492428D01*
G01D02*
X491851Y144498D01*
G01D02*
X491850D01*
G01X521000Y160975D02*
X486156D01*
G01D02*
X486155Y160976D01*
G01D02*
X484975D01*
G01D02*
X477559Y153560D01*
G01X490426Y149900D02*
X522810D01*
G01X481457Y176344D02*
X482748Y175053D01*
G01D02*
Y162648D01*
G01D02*
X480800Y160700D01*
G01X488800Y243500D02*
Y207900D01*
G01D02*
X501200Y195500D01*
G01D02*
Y190400D01*
G01D02*
X516000Y175600D01*
G01X480032Y175753D02*
Y318163D01*
G01X483057Y317156D02*
Y179843D01*
G01D02*
X486600Y176300D01*
G01D02*
X494400D01*
G01X486200Y243700D02*
Y208300D01*
G01D02*
X496073Y198427D01*
G01D02*
Y190642D01*
G01D02*
X503975Y182740D01*
G01X481457Y317572D02*
Y176344D01*
G01X499438Y279380D02*
Y265500D01*
G01D02*
X498624Y264686D01*
G01D02*
Y253324D01*
G01D02*
X488800Y243500D01*
G01X478607Y270712D02*
Y311593D01*
G01X496073Y280729D02*
Y253573D01*
G01D02*
X486200Y243700D01*
G01X497262Y334273D02*
Y281556D01*
G01D02*
X499438Y279380D01*
G01X495837Y334864D02*
Y280965D01*
G01D02*
X496073Y280729D01*
G01X525785Y362796D02*
X497262Y334273D01*
G01X480032Y318163D02*
X482400Y320531D01*
G01D02*
Y335932D01*
G01D02*
X553543Y407075D01*
G01X558229Y404225D02*
X485250Y331246D01*
G01D02*
Y319349D01*
G01D02*
X483057Y317156D01*
G01X478607Y311593D02*
X476890Y313310D01*
G01D02*
Y331095D01*
G01D02*
X478875Y333080D01*
G01D02*
Y334975D01*
G01D02*
X552400Y408500D01*
G01X558820Y402800D02*
X496073Y340053D01*
G01D02*
Y335100D01*
G01D02*
X495837Y334864D01*
G01X554134Y405650D02*
X483825Y335341D01*
G01D02*
Y319940D01*
G01D02*
X481457Y317572D01*
G01X491906Y775148D02*
Y777743D01*
G01D02*
X489522Y780127D01*
G01D02*
X489388Y779993D01*
G01D02*
X485724D01*
G01X503906Y768598D02*
X487744Y752436D01*
G01X487949Y760641D02*
X495906Y768598D01*
G01X500778Y781031D02*
Y780098D01*
G01D02*
X504000Y776876D01*
G01X499906Y775148D02*
X500411Y774643D01*
G01D02*
X504169D01*
G01X489352Y783509D02*
X488505Y782662D01*
G01X488107D02*
X487907Y782462D01*
G01D02*
X482593D01*
G01D02*
X482550Y782505D01*
G01D02*
X476495D01*
G01D02*
X475000Y784000D01*
G01X495906Y775148D02*
Y776820D01*
G01D02*
X497910Y778824D01*
G01X487906Y775148D02*
X486130D01*
G01D02*
X483856Y777422D01*
G01D02*
X482925D01*
G01X495307Y763932D02*
X499906Y768531D01*
G01X495824Y756449D02*
X507906Y768531D01*
G01X482000Y811750D02*
X480750D01*
G01X491900Y788150D02*
X495850D01*
G01D02*
X496000Y788000D01*
G01X491782Y795219D02*
X493686D01*
G01D02*
X496000Y792905D01*
G01D02*
Y788000D01*
G01X480800Y804250D02*
X483331Y801719D01*
G01D02*
X486662D01*
G01X477000Y804000D02*
X480550D01*
G01D02*
X480800Y804250D01*
G01X482000Y808250D02*
X479750D01*
G01D02*
X477000Y805500D01*
G01D02*
Y804000D01*
G01X491900Y784650D02*
X490556D01*
G01D02*
X489415Y783509D01*
G01D02*
X489352D01*
G01X488505Y782662D02*
X488107D01*
G01X475000Y784000D02*
X469000D01*
G01X489222Y801719D02*
Y800036D01*
G01D02*
X487767Y798581D01*
G01D02*
X483381D01*
G01D02*
X481600Y796800D01*
G01X492500Y808250D02*
X489222Y804972D01*
G01D02*
Y801719D01*
G01X502678Y812181D02*
X495688D01*
G01D02*
X493719Y814150D01*
G01D02*
X481134D01*
G01X515339Y815662D02*
X496239D01*
G01D02*
X494901Y817000D01*
G01X478837Y785838D02*
X480100Y784575D01*
G01X492500Y811750D02*
X493750D01*
G01D02*
X494582Y810918D01*
G01D02*
Y804000D01*
G01X502678Y808681D02*
X502359Y809000D01*
G01D02*
X498500D01*
G01X498000Y804250D02*
Y808500D01*
G01D02*
X498500Y809000D01*
G01X514747Y814237D02*
X495648D01*
G01D02*
X494310Y815575D01*
G01D02*
X480543D01*
G01X497000Y817500D02*
X496075Y818425D01*
G01D02*
X493575D01*
G01D02*
X492278Y819722D01*
G01D02*
Y820500D01*
G01X495878Y820681D02*
X492459D01*
G01D02*
X492278Y820500D01*
G01X502621Y833313D02*
X500807Y831499D01*
G01X504488Y831888D02*
X500700Y828100D01*
G01X494901Y817000D02*
X482000D01*
G01D02*
X481000Y818000D01*
G01X480952D02*
X481000D01*
G01X500406Y820648D02*
Y817903D01*
G01D02*
X500415Y817894D01*
G01D02*
Y817532D01*
G01X527104Y64292D02*
Y73196D01*
G01D02*
X523900Y76400D01*
G01X527104Y79252D02*
Y82607D01*
G01D02*
X527764Y83267D01*
G01D02*
Y86752D01*
G01D02*
X518500Y96016D01*
G01D02*
Y116610D01*
G01X523900Y76400D02*
Y81419D01*
G01D02*
X526339Y83858D01*
G01D02*
Y86161D01*
G01D02*
X517075Y95425D01*
G01D02*
Y115725D01*
G01X518500Y116610D02*
X520910Y119020D01*
G01D02*
Y124390D01*
G01X521820Y130320D02*
Y125300D01*
G01D02*
X520910Y124390D01*
G01X521820Y130320D02*
X525820D01*
G01X517820D02*
Y129040D01*
G01D02*
X515220Y126440D01*
G01X513820Y130320D02*
X517820D01*
G01X517075Y115725D02*
X515220Y117580D01*
G01D02*
Y126440D01*
G01X525820Y133820D02*
X529100Y130540D01*
G01D02*
Y125600D01*
G01D02*
X530800Y123900D01*
G01X509369Y141559D02*
Y139655D01*
G01D02*
X513820Y135204D01*
G01D02*
Y133820D01*
G01X525820D02*
X522768Y136872D01*
G01D02*
Y139668D01*
G01D02*
X523500Y140400D01*
G01D02*
Y142301D01*
G01X526125Y154725D02*
X530600Y159200D01*
G01D02*
X539528D01*
G01X541932Y164026D02*
X527226D01*
G01D02*
X522750Y159550D01*
G01X532560Y152046D02*
X536769Y156255D01*
G01X523500Y142301D02*
X520726Y145075D01*
G01X544714Y165514D02*
X525539D01*
G01D02*
X521000Y160975D01*
G01X529176Y151713D02*
X530900Y153437D01*
G01D02*
Y154800D01*
G01D02*
X531900Y155800D01*
G01X503975Y182740D02*
Y172372D01*
G01X522810Y149900D02*
X526321Y146389D01*
G01D02*
X558479D01*
G01X516000Y175600D02*
X564447D01*
G01X532978Y371023D02*
Y369989D01*
G01D02*
X525785Y362796D01*
G01X552600Y418500D02*
X528850Y394750D01*
G01X534500Y395100D02*
X539950Y400550D01*
G01X514900Y742000D02*
X784000D01*
G01X505432Y728500D02*
X872500D01*
G01X781126Y743626D02*
X514226D01*
G01X514943Y748375D02*
X775659D01*
G01X894500Y726000D02*
X504948D01*
G01X515533Y746949D02*
X778949D01*
G01X887500Y731500D02*
X506416D01*
G01X515278Y779198D02*
X517547Y781467D01*
G01D02*
X518328D01*
G01X521900Y774850D02*
X521150D01*
G01D02*
X518328Y777672D01*
G01D02*
Y781467D01*
G01X504000Y776876D02*
Y774812D01*
G01D02*
X504169Y774643D01*
G01X517800Y774950D02*
X517450D01*
G01D02*
X515400Y777000D01*
G01D02*
X512999D01*
G01D02*
X511484Y778515D01*
G01X509600Y774950D02*
X513700D01*
G01X507729Y778198D02*
X507657Y778126D01*
G01D02*
Y775525D01*
G01D02*
X508232Y774950D01*
G01D02*
X509600D01*
G01X507729Y778198D02*
Y779001D01*
G01D02*
X513473Y784745D01*
G01X527000Y774950D02*
Y781376D01*
G01D02*
X528179Y782555D01*
G01D02*
X529289Y781445D01*
G01D02*
Y779901D01*
G01D02*
X530590Y778600D01*
G01D02*
X531500D01*
G01X532632Y787632D02*
Y779732D01*
G01D02*
X531500Y778600D01*
G01X505600Y787350D02*
Y780520D01*
G01D02*
X504278Y779198D01*
G01X524795Y778529D02*
X524700Y778434D01*
G01D02*
Y764100D01*
G01D02*
X516100Y755500D01*
G01D02*
X509474D01*
G01X524689Y782937D02*
Y778635D01*
G01D02*
X524795Y778529D01*
G01X514000Y799250D02*
X515250D01*
G01D02*
X517750Y801750D01*
G01D02*
X519440D01*
G01X516500Y808000D02*
Y807440D01*
G01D02*
X519440Y804500D01*
G01D02*
Y801750D01*
G01X520178Y808681D02*
X517181D01*
G01D02*
X516500Y808000D01*
G01X506678Y808681D02*
X507497Y809500D01*
G01D02*
X509500D01*
G01D02*
X510500Y808500D01*
G01X506000Y801750D02*
Y804500D01*
G01D02*
X507000Y805500D01*
G01D02*
X509000D01*
G01D02*
X510500Y807000D01*
G01D02*
Y808500D01*
G01X510450Y788700D02*
Y786450D01*
G01D02*
X508700Y784700D01*
G01X508560Y795250D02*
Y791900D01*
G01D02*
X510450Y790010D01*
G01D02*
Y788700D01*
G01X534678Y808681D02*
X530012Y804015D01*
G01D02*
Y803025D01*
G01X535440Y801750D02*
Y805738D01*
G01D02*
X534678Y806500D01*
G01D02*
Y808681D01*
G01X530000Y799250D02*
X530012Y799262D01*
G01D02*
Y803025D01*
G01X516943Y817401D02*
X518682Y815662D01*
G01D02*
X532500D01*
G01D02*
X533838Y817000D01*
G01X524178Y808681D02*
X525117Y809620D01*
G01D02*
X527948D01*
G01X522000Y801750D02*
Y806503D01*
G01D02*
X524178Y808681D01*
G01X513473Y784745D02*
X514298D01*
G01X506678Y812181D02*
X507309Y812812D01*
G01D02*
X513000D01*
G01D02*
X513338Y812474D01*
G01D02*
Y801781D01*
G01D02*
X510698Y799141D01*
G01D02*
Y793702D01*
G01D02*
X512812Y791588D01*
G01D02*
Y786231D01*
G01D02*
X514298Y784745D01*
G01X534678Y812181D02*
X532622Y814237D01*
G01D02*
X516764D01*
G01D02*
X515339Y815662D01*
G01X503440Y801750D02*
Y805060D01*
G01D02*
X502678Y805822D01*
G01D02*
Y808681D01*
G01X520178Y812181D02*
X516803D01*
G01D02*
X514747Y814237D01*
G01X524678Y788181D02*
X524859Y788000D01*
G01D02*
X528500D01*
G01X524560Y795250D02*
Y788299D01*
G01D02*
X524678Y788181D01*
G01X524178Y812181D02*
X524881D01*
G01D02*
X525512Y812812D01*
G01D02*
X530688D01*
G01D02*
X531900Y811600D01*
G01D02*
Y808400D01*
G01D02*
X526548Y803048D01*
G01D02*
Y793035D01*
G01D02*
X528812Y790771D01*
G01D02*
X529493D01*
G01D02*
X532632Y787632D01*
G01X506950Y788700D02*
X505600Y787350D01*
G01X524678Y784681D02*
Y784125D01*
G01D02*
X524688Y784115D01*
G01D02*
Y782938D01*
G01D02*
X524689Y782937D01*
G01X592386Y775062D02*
X534135Y833313D01*
G01D02*
X502621D01*
G01X516906Y820648D02*
Y817438D01*
G01D02*
X516943Y817401D01*
G01X533838Y817000D02*
X537500D01*
G01X594892Y768524D02*
X532953Y830463D01*
G01D02*
X511621D01*
G01D02*
X508579Y827421D01*
G01X512679Y820600D02*
Y818079D01*
G01D02*
X512672Y818072D01*
G01D02*
Y817624D01*
G01D02*
X512716Y817580D01*
G01D02*
Y817550D01*
G01X593633Y767099D02*
X531694Y829038D01*
G01D02*
X514217D01*
G01D02*
X512679Y827500D01*
G01X595482Y769950D02*
X533544Y831888D01*
G01D02*
X504488D01*
G01X524700Y817500D02*
X522000D01*
G01D02*
X521000Y818500D01*
G01D02*
Y820000D01*
G01X524906Y820648D02*
X521648D01*
G01D02*
X521000Y820000D01*
G01X532678Y889470D02*
Y841378D01*
G01D02*
X527500Y836200D01*
G01X528906Y817598D02*
X529004Y817500D01*
G01D02*
X532000D01*
G01D02*
X532506Y818006D01*
G01D02*
Y820000D01*
G01X528906Y820648D02*
X531858D01*
G01D02*
X532506Y820000D01*
G01X507044Y817569D02*
X505431D01*
G01D02*
X504241Y818759D01*
G01D02*
Y820278D01*
G01X508579Y820600D02*
X504563D01*
G01D02*
X504241Y820278D01*
G01X570411Y71589D02*
X568000Y74000D01*
G01D02*
Y81000D01*
G01X571071Y87945D02*
X567090Y91926D01*
G01D02*
X567074D01*
G01D02*
X562350Y96650D01*
G01D02*
Y105060D01*
G01D02*
X577336Y120046D01*
G01X568000Y81000D02*
X569646Y82646D01*
G01D02*
Y87354D01*
G01D02*
X566499Y90501D01*
G01D02*
X566483D01*
G01D02*
X560925Y96059D01*
G01D02*
Y105651D01*
G01D02*
X573055Y117781D01*
G01X566615Y141980D02*
Y141475D01*
G01D02*
X570345Y137745D01*
G01X564447Y175600D02*
X571316Y168731D01*
G01X539528Y159200D02*
X542090Y156638D01*
G01D02*
X557028D01*
G01D02*
X558690Y158300D01*
G01D02*
X609217D01*
G01X606067Y163125D02*
X556689D01*
G01D02*
X555027Y161463D01*
G01D02*
X544495D01*
G01D02*
X541932Y164026D01*
G01X536769Y156255D02*
X538158D01*
G01X547173Y167987D02*
Y167973D01*
G01D02*
X544714Y165514D01*
G01X566531Y143123D02*
Y142064D01*
G01D02*
X566615Y141980D01*
G01X558479Y146389D02*
X559791Y147701D01*
G01D02*
X560971D01*
G01D02*
X560972Y147700D01*
G01D02*
X570419D01*
G01X555801Y250511D02*
X569912Y236400D01*
G01X572196Y232100D02*
X553219Y251077D01*
G01X580930Y215770D02*
X569345Y227355D01*
G01D02*
Y230919D01*
G01D02*
X550369Y249895D01*
G01X551794Y250486D02*
X570771Y231509D01*
G01X555801Y299699D02*
Y250511D01*
G01X553219Y251077D02*
Y299581D01*
G01X550369Y249895D02*
Y297931D01*
G01X551794Y298806D02*
Y250486D01*
G01X550882Y370281D02*
Y304618D01*
G01D02*
X555801Y299699D01*
G01X553219Y299581D02*
X548075Y304725D01*
G01D02*
Y381674D01*
G01X550369Y297931D02*
X545225Y303075D01*
G01D02*
Y382856D01*
G01X546650Y382265D02*
Y303950D01*
G01D02*
X551794Y298806D01*
G01X560531Y364830D02*
Y368731D01*
G01D02*
X561300Y369500D01*
G01X604326Y423725D02*
X550882Y370281D01*
G01X561912Y390762D02*
X562276Y390398D01*
G01D02*
X568814D01*
G01D02*
X603741Y425325D01*
G01X553543Y407075D02*
X564348D01*
G01D02*
X594549Y437276D01*
G01X593755Y432450D02*
X565530Y404225D01*
G01D02*
X558229D01*
G01X548075Y381674D02*
X563326Y396925D01*
G01D02*
X573325D01*
G01X552400Y408500D02*
X559900D01*
G01D02*
X567150Y415750D01*
G01X545225Y382856D02*
X562144Y399775D01*
G01D02*
X572143D01*
G01X594346Y431025D02*
X566121Y402800D01*
G01D02*
X558820D01*
G01X539950Y400550D02*
X540150D01*
G01D02*
X556675Y417075D01*
G01X572734Y398350D02*
X562735D01*
G01D02*
X546650Y382265D01*
G01X595140Y435851D02*
X564939Y405650D01*
G01D02*
X554134D01*
G01X589593Y442188D02*
X563055Y415650D01*
G01D02*
X562850D01*
G01D02*
X560900Y413700D01*
G01X588412Y445039D02*
X561873Y418500D01*
G01D02*
X552600D01*
G01X556675Y417075D02*
X562464D01*
G01D02*
X589003Y443614D01*
G01X540500Y781000D02*
X544500D01*
G01D02*
X545500Y782000D01*
G01D02*
Y783500D01*
G01X542800Y812550D02*
X542431Y812181D01*
G01D02*
X538678D01*
G01X537500Y817000D02*
X538678Y815822D01*
G01D02*
Y812181D01*
G01X538000Y801750D02*
Y799499D01*
G01D02*
X539111Y798388D01*
G01D02*
X544788D01*
G01D02*
X546200Y799800D01*
G01X538678Y808681D02*
Y806500D01*
G01D02*
X538000Y805822D01*
G01D02*
Y801750D01*
G01X540678Y788181D02*
X544181D01*
G01D02*
X546000Y790000D01*
G01D02*
Y793000D01*
G01X540560Y795250D02*
X543750D01*
G01D02*
X546000Y793000D01*
G01X540678Y784681D02*
X544319D01*
G01D02*
X545500Y783500D01*
G01X570411Y64292D02*
Y71589D01*
G01Y79252D02*
Y81395D01*
G01D02*
X571071Y82055D01*
G01D02*
Y87945D01*
G01X577336Y120046D02*
Y125424D01*
G01X578467Y130280D02*
X582467D01*
G01X578467D02*
X577336Y129149D01*
G01D02*
Y125424D01*
G01X573055Y121869D02*
Y125276D01*
G01D02*
X575866Y128087D01*
G01D02*
Y128759D01*
G01D02*
X574345Y130280D01*
G01D02*
X570345D01*
G01X573055Y117781D02*
Y121869D01*
G01X582467Y133780D02*
X581600Y134647D01*
G01D02*
Y142101D01*
G01X570345Y137745D02*
Y133780D01*
G01X571316Y168731D02*
X636099D01*
G01X581600Y142101D02*
X576336Y147365D01*
G01D02*
X570754D01*
G01X570419Y147700D02*
X570754Y147365D01*
G01X569912Y236400D02*
X573300D01*
G01D02*
X575200Y234500D01*
G01D02*
X576100D01*
G01X630952Y218620D02*
X582112D01*
G01D02*
X572196Y228536D01*
G01D02*
Y232100D01*
G01X629770Y215770D02*
X580930D01*
G01X570771Y231509D02*
Y227945D01*
G01D02*
X581521Y217195D01*
G01D02*
X630361D01*
G01X573325Y396925D02*
X603150Y426750D01*
G01X572143Y399775D02*
X601968Y429600D01*
G01X602559Y428175D02*
X572734Y398350D01*
G01X594549Y437276D02*
X1309288D01*
G01X1280349Y432450D02*
X593755D01*
G01X1316406Y442189D02*
X593093Y442188D01*
G01D02*
X589593D01*
G01X603150Y426750D02*
X1270428D01*
G01X601968Y429600D02*
X1279167D01*
G01X1279758Y431025D02*
X594346D01*
G01X1317588Y445039D02*
X588412D01*
G01X589003Y443614D02*
X1316997D01*
G01X1278576Y428175D02*
X602559D01*
G01X1308697Y435851D02*
X595140D01*
G01X658762Y775062D02*
X592386D01*
G01X661024Y768524D02*
X594892D01*
G01X663399Y767099D02*
X593633D01*
G01X658250Y769950D02*
X595482D01*
G01X613718Y64292D02*
Y72282D01*
G01D02*
X611530Y74470D01*
G01X613718Y79252D02*
Y82606D01*
G01D02*
X614379Y83267D01*
G01D02*
Y88547D01*
G01D02*
X607150Y95776D01*
G01D02*
Y107662D01*
G01D02*
X616614Y117126D01*
G01X611530Y74470D02*
Y82434D01*
G01D02*
X612954Y83858D01*
G01D02*
Y87956D01*
G01D02*
X605725Y95185D01*
G01D02*
Y108253D01*
G01X616614Y117126D02*
Y123871D01*
G01X620048Y130494D02*
X616614Y127060D01*
G01D02*
Y123871D01*
G01X620048Y130494D02*
X624048D01*
G01X612026Y134002D02*
Y135389D01*
G01D02*
X614721Y138084D01*
G01D02*
Y138287D01*
G01X624048Y133994D02*
X623345D01*
G01D02*
X619090Y138249D01*
G01D02*
Y140950D01*
G01D02*
X616900Y143140D01*
G01X605725Y108253D02*
X611642Y114170D01*
G01D02*
Y123340D01*
G01D02*
Y130118D01*
G01D02*
X612026Y130502D01*
G01D02*
X616026D01*
G01X636099Y168731D02*
X700226Y104604D01*
G01X609777Y158860D02*
X615500Y153137D01*
G01D02*
Y146300D01*
G01D02*
X617000Y144800D01*
G01D02*
Y144500D01*
G01X616900Y143140D02*
Y144450D01*
G01D02*
X616950Y144500D01*
G01D02*
X617000D01*
G01X609217Y158300D02*
X609777Y158860D01*
G01X649500Y152384D02*
X637386Y164498D01*
G01D02*
X607440D01*
G01D02*
X606067Y163125D01*
G01X641972Y214470D02*
X635102D01*
G01D02*
X630952Y218620D01*
G01X651794Y211620D02*
X633920D01*
G01D02*
X629770Y215770D01*
G01X630361Y217195D02*
X634511Y213045D01*
G01D02*
X652385D01*
G01X603741Y425325D02*
X1258085D01*
G01X1237305Y423725D02*
X604326D01*
G01X1196600Y422300D02*
X605500D01*
G01D02*
X604400Y421200D01*
G01X1178200Y420300D02*
X615700D01*
G01D02*
X615500Y420100D01*
G01X636615Y889470D02*
Y856085D01*
G01D02*
X641000Y851700D01*
G01X657025Y64292D02*
Y71475D01*
G01D02*
X654837Y73663D01*
G01D02*
Y82434D01*
G01D02*
X656261Y83858D01*
G01D02*
Y85670D01*
G01D02*
X649692Y92239D01*
G01D02*
Y125160D01*
G01X657025Y79252D02*
Y82606D01*
G01D02*
X657686Y83267D01*
G01D02*
Y86261D01*
G01D02*
X651117Y92830D01*
G01D02*
Y120767D01*
G01X650500Y133750D02*
X649500Y134750D01*
G01D02*
Y152384D01*
G01X650500Y133750D02*
X655000D01*
G01X650500Y130250D02*
X646000D01*
G01X650500D02*
X649692Y129442D01*
G01D02*
Y125160D01*
G01X655000Y130250D02*
X659500D01*
G01X655000D02*
Y125360D01*
G01X651117Y120767D02*
X655000Y124650D01*
G01D02*
Y125360D01*
G01X687663Y208337D02*
X655077D01*
G01D02*
X651794Y211620D01*
G01X660700Y212000D02*
X659544D01*
G01D02*
X657338Y214206D01*
G01D02*
Y214261D01*
G01D02*
X656261Y215338D01*
G01D02*
X642840D01*
G01D02*
X641972Y214470D01*
G01X652385Y213045D02*
X653609Y211821D01*
G01D02*
X653610D01*
G01D02*
X655669Y209762D01*
G01D02*
X667517D01*
G01D02*
X670363Y212608D01*
G01D02*
X671885D01*
G01X645800Y780500D02*
Y781100D01*
G01D02*
X643538Y783362D01*
G01X695049Y811349D02*
X658762Y775062D01*
G01X691487Y798987D02*
X661024Y768524D01*
G01X645800Y776900D02*
X641000Y781700D01*
G01D02*
Y816500D01*
G01X688212Y791912D02*
X663399Y767099D01*
G01X693243Y804943D02*
X658250Y769950D01*
G01X643538Y783362D02*
Y803500D01*
G01Y851178D02*
Y803500D01*
G01X646800Y788200D02*
Y811500D01*
G01X645800Y783900D02*
X646800Y784900D01*
G01D02*
Y788200D01*
G01Y849932D02*
Y811500D01*
G01X641000Y851700D02*
Y816500D01*
G01X642914Y853818D02*
X646800Y849932D01*
G01X639764Y889470D02*
Y880302D01*
G01D02*
X639075Y879613D01*
G01D02*
Y855641D01*
G01D02*
X643538Y851178D01*
G01X642914Y889470D02*
Y882214D01*
G01D02*
X640462Y879762D01*
G01D02*
Y877180D01*
G01D02*
X640500Y877142D01*
G01D02*
Y870014D01*
G01D02*
X642914Y867600D01*
G01D02*
Y853818D01*
G01X700226Y76474D02*
X715200Y61500D01*
G01X700226Y104604D02*
Y76474D01*
G01X687900Y208100D02*
X687663Y208337D01*
G01X671885Y212608D02*
X672493Y212000D01*
G01D02*
X674500D01*
G01X695049Y811349D02*
X701000Y817300D01*
G01X711100Y818600D02*
X691487Y798987D01*
G01X712495Y816195D02*
X688212Y791912D01*
G01X727200Y838900D02*
X693243Y804943D01*
G01X701000Y817300D02*
X724450Y840750D01*
G01X734738Y47399D02*
Y23963D01*
G01D02*
X759701Y-1000D01*
G01X720100Y38050D02*
X718215D01*
G01D02*
X717401Y37236D01*
G01D02*
X715613D01*
G01D02*
X715130Y37719D01*
G01D02*
Y45650D01*
G01X711510Y13930D02*
Y14130D01*
G01D02*
X715300Y17920D01*
G01X715380Y22030D02*
Y18000D01*
G01D02*
X715300Y17920D01*
G01X715390Y33130D02*
X715830D01*
G01D02*
X718500Y35800D01*
G01D02*
X720835D01*
G01D02*
X721938Y36903D01*
G01D02*
X728343D01*
G01D02*
X732900Y41460D01*
G01X715200Y61500D02*
X724716D01*
G01D02*
X732392Y53824D01*
G01D02*
Y49745D01*
G01D02*
X734738Y47399D01*
G01X732900Y41460D02*
Y44900D01*
G01X730021Y42235D02*
X729975D01*
G01D02*
X729500Y42710D01*
G01D02*
Y54700D01*
G01D02*
X726300Y57900D01*
G01D02*
X716380D01*
G01D02*
X715130Y56650D01*
G01X724450Y840750D02*
Y871700D01*
G01X714900Y818600D02*
X711100D01*
G01X727200Y873900D02*
Y838900D01*
G01X724450Y871700D02*
X724738Y871988D01*
G01D02*
Y878962D01*
G01D02*
X721654Y882046D01*
G01D02*
Y889470D01*
G01X724804D02*
Y880134D01*
G01D02*
X725875Y879063D01*
G01D02*
Y875225D01*
G01D02*
X727200Y873900D01*
G01X759701Y-1000D02*
X774497D01*
G01X741600Y34439D02*
Y21897D01*
G01D02*
X752697Y10800D01*
G01D02*
X767755D01*
G01D02*
X771715Y6840D01*
G01X741600Y41000D02*
Y34439D01*
G01X768777Y171450D02*
Y163607D01*
G01D02*
X829500Y102884D01*
G01X774497Y-1000D02*
X781774Y-8277D01*
G01D02*
X824238D01*
G01X790150Y-1400D02*
Y3434D01*
G01D02*
X801100Y14384D01*
G01X799675Y14975D02*
X787600Y2900D01*
G01D02*
Y-3513D01*
G01D02*
X788408Y-4321D01*
G01X801100Y14384D02*
Y17400D01*
G01D02*
X815976Y32276D01*
G01X811937Y41381D02*
X799675Y29119D01*
G01D02*
Y14975D01*
G01X784000Y742000D02*
X816750Y774750D01*
G01X817405Y779905D02*
X781126Y743626D01*
G01X775659Y748375D02*
X799459Y772175D01*
G01X778949Y746949D02*
X808584Y776584D01*
G01X821632Y794348D02*
X799459Y772175D01*
G01X824238Y-8277D02*
X824427Y-8088D01*
G01D02*
X889925D01*
G01X807514Y2199D02*
Y13310D01*
G01X830252Y17750D02*
X831551D01*
G01D02*
X832390Y18589D01*
G01D02*
Y21289D01*
G01D02*
X833279Y22178D01*
G01D02*
Y24708D01*
G01D02*
X833246Y24741D01*
G01X830500Y20800D02*
X830478Y20822D01*
G01D02*
Y22889D01*
G01D02*
X831152Y23563D01*
G01D02*
Y23634D01*
G01D02*
X832259Y24741D01*
G01D02*
X833246D01*
G01X824462Y25770D02*
X823730Y26502D01*
G01D02*
X821921D01*
G01D02*
X819052Y23633D01*
G01D02*
X818500Y23081D01*
G01D02*
Y19221D01*
G01D02*
X820052Y17669D01*
G01D02*
X820212D01*
G01X815976Y32276D02*
X823600Y39900D01*
G01D02*
Y43880D01*
G01X838252Y17750D02*
Y20800D01*
G01D02*
X838787Y21335D01*
G01D02*
Y27101D01*
G01D02*
X838881Y27195D01*
G01X826141Y21594D02*
X826146Y21589D01*
G01D02*
Y17062D01*
G01D02*
X826138Y17054D01*
G01X828283Y24734D02*
Y23736D01*
G01D02*
X826141Y21594D01*
G01X807514Y13310D02*
X808838Y14634D01*
G01D02*
Y21733D01*
G01D02*
X827727Y40622D01*
G01X834252Y17750D02*
Y20552D01*
G01D02*
X834500Y20800D01*
G01X823600Y43880D02*
X823996Y44276D01*
G01X829500Y79889D02*
X845113Y64276D01*
G01X827727Y43554D02*
Y47827D01*
G01D02*
X828700Y48800D01*
G01X827727Y40622D02*
Y43554D01*
G01X820004Y44234D02*
X819581Y43811D01*
G01D02*
X814367D01*
G01D02*
X811937Y41381D01*
G01X845704Y65701D02*
X839000Y72405D01*
G01D02*
Y82100D01*
G01X829500Y102884D02*
Y79889D01*
G01X839000Y82100D02*
X844550Y87650D01*
G01X826979Y657925D02*
X885442Y599462D01*
G01X886033Y600887D02*
X827570Y659350D01*
G01X833375Y665625D02*
X875252Y623748D01*
G01X830300Y664200D02*
X880889Y613611D01*
G01X828752Y662200D02*
X887215Y603737D01*
G01X828161Y660775D02*
X886624Y602312D01*
G01X837000Y774750D02*
X831500D01*
G01X816750D02*
X831500D01*
G01X838100Y783400D02*
X841000Y780500D01*
G01X836300Y783300D02*
Y778950D01*
G01D02*
X837000Y778250D01*
G01X817405Y779905D02*
X828998Y791498D01*
G01X824923Y792923D02*
X808584Y776584D01*
G01X836300Y783300D02*
X836400Y783400D01*
G01D02*
X838100D01*
G01X828998Y791498D02*
X853912D01*
G01X862912Y794348D02*
X821632D01*
G01X816142Y837858D02*
X839500Y814500D01*
G01D02*
X864000D01*
G01X862321Y792923D02*
X824923D01*
G01X825591Y889470D02*
Y835046D01*
G01D02*
X837299Y823338D01*
G01D02*
X863500D01*
G01X819292Y872500D02*
Y837208D01*
G01D02*
X839138Y817362D01*
G01D02*
X853500D01*
G01X816142Y889470D02*
Y837858D01*
G01X822441Y889470D02*
Y836180D01*
G01D02*
X838121Y820500D01*
G01D02*
X845500D01*
G01X819292Y889470D02*
Y882992D01*
G01D02*
X818000Y881700D01*
G01D02*
Y873792D01*
G01D02*
X819292Y872500D01*
G01X850900Y16200D02*
Y17448D01*
G01D02*
X854252Y20800D01*
G01X856650Y16200D02*
X850900D01*
G01X846252Y17750D02*
Y19848D01*
G01D02*
X845300Y20800D01*
G01D02*
X845052D01*
G01D02*
Y21495D01*
G01D02*
X848519Y24962D01*
G01D02*
X848520Y24961D01*
G01D02*
X848545D01*
G01X870600Y18915D02*
Y16509D01*
G01D02*
X871800Y15309D01*
G01X842252Y17750D02*
Y19948D01*
G01D02*
X841652Y20548D01*
G01D02*
Y20800D01*
G01D02*
X843545Y22693D01*
G01D02*
Y25012D01*
G01X873100Y30750D02*
X873060Y30790D01*
G01D02*
Y37350D01*
G01X877300Y30750D02*
X873100D01*
G01D02*
X870911Y28561D01*
G01D02*
X864061D01*
G01D02*
X863500Y28000D01*
G01X849051Y20908D02*
X850708D01*
G01D02*
X853100Y23300D01*
G01D02*
X858800D01*
G01D02*
X863500Y28000D01*
G01X870500Y37350D02*
Y39700D01*
G01D02*
X871512Y40712D01*
G01X855421Y70551D02*
Y78094D01*
G01X848623Y74557D02*
Y70757D01*
G01X868800Y49200D02*
X867600Y50400D01*
G01D02*
X866025D01*
G01D02*
X865004Y49379D01*
G01X867940Y43850D02*
X866150D01*
G01D02*
X864900Y45100D01*
G01D02*
Y49275D01*
G01D02*
X865004Y49379D01*
G01X845113Y64276D02*
X862876D01*
G01D02*
X866362Y67762D01*
G01D02*
X919262D01*
G01X852019Y70589D02*
Y76708D01*
G01X858821Y75500D02*
Y70614D01*
G01X918709Y69225D02*
X865809D01*
G01D02*
X862285Y65701D01*
G01D02*
X845704D01*
G01X871512Y40712D02*
X878888D01*
G01X878062Y95038D02*
X869538D01*
G01D02*
X866919Y92419D01*
G01X855421Y78094D02*
X862000Y84673D01*
G01D02*
Y87500D01*
G01D02*
X866919Y92419D01*
G01X883862Y97888D02*
X864754D01*
G01D02*
X855897Y89031D01*
G01D02*
Y82602D01*
G01D02*
X848623Y75328D01*
G01D02*
Y74557D01*
G01X875000Y83334D02*
X871696Y86638D01*
G01D02*
Y87082D01*
G01X875000Y89220D02*
X872862Y87082D01*
G01D02*
X871696D01*
G01X852019Y76708D02*
X859000Y83689D01*
G01D02*
Y86500D01*
G01X882237Y96463D02*
X866963D01*
G01D02*
X859000Y88500D01*
G01D02*
Y86500D01*
G01X875000Y93250D02*
X872593D01*
G01D02*
X858821Y79478D01*
G01D02*
Y75500D01*
G01X844550Y87650D02*
X848100D01*
G01X852400Y87550D02*
X869520Y104670D01*
G01D02*
X875070D01*
G01X852400Y87550D02*
X852300Y87650D01*
G01D02*
X848100D01*
G01X866000Y82500D02*
Y83200D01*
G01D02*
X868100Y85300D01*
G01D02*
X868800D01*
G01X871000Y82250D02*
X869829Y81079D01*
G01D02*
X867421D01*
G01D02*
X866000Y82500D01*
G01X848600Y753300D02*
Y745500D01*
G01D02*
X850799Y743301D01*
G01X894600Y737200D02*
X856900D01*
G01D02*
X850799Y743301D01*
G01X905900Y728500D02*
X872500D01*
G01X896500Y734000D02*
X854000D01*
G01D02*
X844500Y743500D01*
G01D02*
Y750000D01*
G01X851782Y772719D02*
X852669Y771832D01*
G01D02*
Y771678D01*
G01D02*
X856576Y767771D01*
G01X852400Y765650D02*
X854455D01*
G01D02*
X856576Y767771D01*
G01X860906Y752148D02*
Y754698D01*
G01D02*
X861406Y755198D01*
G01X854049Y757573D02*
X852873D01*
G01D02*
X848600Y753300D01*
G01X841000Y778250D02*
X843350D01*
G01D02*
X844319Y779219D01*
G01D02*
X846662D01*
G01X841000Y780500D02*
Y778250D01*
G01X857500Y781750D02*
Y785660D01*
G01Y781750D02*
X858120Y781130D01*
G01D02*
X859480D01*
G01D02*
X861860Y778750D01*
G01D02*
X862940D01*
G01X870150Y765800D02*
Y761795D01*
G01D02*
X871417Y760528D01*
G01D02*
Y753787D01*
G01D02*
X872513Y752691D01*
G01D02*
X873700D01*
G01X865500Y778750D02*
Y783740D01*
G01X849222Y779219D02*
Y781708D01*
G01D02*
X845090Y785840D01*
G01X852400Y762150D02*
Y760400D01*
G01D02*
X849500Y757500D01*
G01D02*
X845000D01*
G01D02*
X844500Y758000D01*
G01D02*
Y750000D01*
G01X866650Y765800D02*
Y762870D01*
G01D02*
X867640Y761880D01*
G01X868060Y772250D02*
Y769200D01*
G01D02*
X866650Y767790D01*
G01D02*
Y765800D01*
G01X856906Y752148D02*
X852352D01*
G01D02*
X851500Y753000D01*
G01X857406Y755198D02*
X853698D01*
G01D02*
X851500Y753000D01*
G01X868100Y783500D02*
X872838Y778762D01*
G01D02*
Y775739D01*
G01D02*
X871812Y774713D01*
G01D02*
Y768793D01*
G01D02*
X872039Y768566D01*
G01D02*
Y761936D01*
G01D02*
X872901Y761074D01*
G01D02*
Y756155D01*
G01D02*
X873487Y755569D01*
G01D02*
X875948D01*
G01X868906Y752148D02*
X869620Y752862D01*
G01D02*
Y758299D01*
G01D02*
X869517Y758402D01*
G01D02*
Y758412D01*
G01D02*
X869562Y758457D01*
G01X872617Y750235D02*
X872172Y750680D01*
G01D02*
X870374D01*
G01D02*
X868906Y752148D01*
G01X867410Y755824D02*
X865134Y758100D01*
G01D02*
X864366D01*
G01X864906Y752148D02*
X864366Y752688D01*
G01D02*
Y758100D01*
G01X870400Y789150D02*
X872450D01*
G01D02*
X874800Y786800D01*
G01X858020Y786180D02*
X858690Y786850D01*
G01D02*
Y790220D01*
G01X857500Y785660D02*
X858020Y786180D01*
G01X839990Y789230D02*
X844700D01*
G01D02*
X844810Y789340D01*
G01X869906Y797648D02*
Y794903D01*
G01D02*
X870278Y794531D01*
G01X853912Y791498D02*
X855190Y790220D01*
G01X874100Y794860D02*
X871890Y792650D01*
G01D02*
X864610D01*
G01D02*
X862912Y794348D01*
G01X864000Y814500D02*
X881100D01*
G01X874242Y791220D02*
X864024D01*
G01D02*
X862321Y792923D01*
G01X865500Y783740D02*
X864147Y785093D01*
G01X862810Y788880D02*
Y786430D01*
G01D02*
X864147Y785093D01*
G01X845090Y785840D02*
X844810D01*
G01X840960Y785260D02*
X844230D01*
G01D02*
X844810Y785840D01*
G01X866878Y794531D02*
X865195D01*
G01D02*
X863724Y796002D01*
G01D02*
X862498D01*
G01D02*
X861500Y797000D01*
G01X865378Y797681D02*
X862181D01*
G01D02*
X861500Y797000D01*
G01X866310Y788880D02*
X868100Y787090D01*
G01D02*
Y783500D01*
G01X857087Y870000D02*
Y842029D01*
G01D02*
X871891Y827225D01*
G01D02*
X898391D01*
G01X888100Y823338D02*
X863500D01*
G01X887362Y818680D02*
X868978D01*
G01D02*
X867660Y817362D01*
G01D02*
X853500D01*
G01X888900Y820500D02*
X845500D01*
G01X853937Y871134D02*
Y843163D01*
G01D02*
X871300Y825800D01*
G01D02*
X897800D01*
G01X857087Y889470D02*
Y883787D01*
G01D02*
X854000Y880700D01*
G01D02*
Y873087D01*
G01D02*
X857087Y870000D01*
G01X853937Y889470D02*
Y883137D01*
G01D02*
X852500Y881700D01*
G01D02*
Y872571D01*
G01D02*
X853937Y871134D01*
G01X889925Y-8088D02*
X902388Y4375D01*
G01D02*
Y13737D01*
G01D02*
X901746Y14379D01*
G01D02*
Y17385D01*
G01D02*
X908262Y23901D01*
G01X905488Y48573D02*
Y38665D01*
G01D02*
X918284Y25869D01*
G01X888200Y30500D02*
X892500D01*
G01D02*
X893100Y31100D01*
G01D02*
Y34650D01*
G01X878888Y40712D02*
X883500Y36100D01*
G01D02*
Y32000D01*
G01D02*
X885000Y30500D01*
G01D02*
X888200D01*
G01X905488Y54479D02*
Y48573D01*
G01X883800Y41400D02*
Y46638D01*
G01D02*
X885538Y48376D01*
G01D02*
Y51962D01*
G01D02*
X882949Y54551D01*
G01D02*
X882429D01*
G01X879500Y44900D02*
X876962Y47438D01*
G01D02*
Y50361D01*
G01D02*
X881152Y54551D01*
G01D02*
X882429D01*
G01X906500Y82250D02*
X905550D01*
G01D02*
Y82291D01*
G01D02*
X901899Y85942D01*
G01X906500Y89750D02*
X905707D01*
G01D02*
X901899Y85942D01*
G01X879500Y93250D02*
Y93600D01*
G01D02*
X878062Y95038D01*
G01X888500Y93250D02*
X883862Y97888D01*
G01X902000Y82250D02*
X901000D01*
G01D02*
X897750Y85500D01*
G01D02*
X902000Y89750D01*
G01X897600Y85500D02*
X897750D01*
G01X897500Y93250D02*
X902169Y97919D01*
G01X920066Y114481D02*
X906700Y101115D01*
G01D02*
X905365D01*
G01D02*
X902169Y97919D01*
G01X888500Y82250D02*
X888084D01*
G01D02*
X885042Y85292D01*
G01X888500Y89750D02*
Y88750D01*
G01D02*
X885042Y85292D01*
G01X908676Y99926D02*
X902000Y93250D01*
G01X875000Y82250D02*
Y83334D01*
G01Y89750D02*
Y89220D01*
G01X884000Y93250D02*
Y94700D01*
G01D02*
X882237Y96463D01*
G01X897500Y82250D02*
X896350D01*
G01D02*
X893300Y85300D01*
G01D02*
X893050D01*
G01D02*
X892900D01*
G01X897500Y89750D02*
X893050Y85300D01*
G01X893000Y93250D02*
Y99400D01*
G01D02*
X894533Y100933D01*
G01X917700Y114131D02*
X906109Y102540D01*
G01D02*
X896140D01*
G01D02*
X894533Y100933D01*
G01X879500Y82250D02*
X878650D01*
G01D02*
X875445Y85455D01*
G01D02*
Y85559D01*
G01D02*
X875001Y86003D01*
G01X879500Y89750D02*
X879208D01*
G01D02*
X875461Y86003D01*
G01D02*
X875001D01*
G01X884000Y82250D02*
X882693D01*
G01D02*
X879163Y85780D01*
G01D02*
X878394D01*
G01X884000Y89750D02*
X881750Y87500D01*
G01D02*
X880000D01*
G01D02*
X878394Y85894D01*
G01D02*
Y85780D01*
G01X893000Y89750D02*
X888950Y85700D01*
G01D02*
X888600D01*
G01X893000Y82250D02*
X889550Y85700D01*
G01D02*
X888950D01*
G01X875070Y104670D02*
X900779D01*
G01D02*
X905180Y109071D01*
G01X906500Y93250D02*
X915926Y102676D01*
G01X903920Y137780D02*
Y140060D01*
G01D02*
X901969Y142011D01*
G01X902150Y112500D02*
X900000D01*
G01D02*
X898000Y114500D01*
G01D02*
Y117000D01*
G01X901969Y147638D02*
Y147634D01*
G01D02*
X903937Y145666D01*
G01X903970Y157478D02*
Y153576D01*
G01D02*
X901969Y151575D01*
G01Y142011D02*
Y143701D01*
G01X953500Y607000D02*
X892000D01*
G01D02*
X875252Y623748D01*
G01X958178Y605162D02*
X889338D01*
G01D02*
X880889Y613611D01*
G01X885442Y599462D02*
X1275462D01*
G01X887215Y603737D02*
X1269336D01*
G01X1272387Y600887D02*
X886033D01*
G01X886624Y602312D02*
X1269927D01*
G01X1004800Y622300D02*
X899684D01*
G01D02*
X892100Y629884D01*
G01D02*
Y694000D01*
G01X1005391Y620875D02*
X899093D01*
G01D02*
X888550Y631418D01*
G01D02*
Y702000D01*
G01X1004209Y623725D02*
X900275D01*
G01D02*
X896000Y628000D01*
G01D02*
Y686000D01*
G01X1006573Y618025D02*
X897911D01*
G01D02*
X881200Y634736D01*
G01D02*
Y713500D01*
G01X1005982Y619450D02*
X898502D01*
G01D02*
X884700Y633252D01*
G01D02*
Y708000D01*
G01X892100Y694000D02*
Y721100D01*
G01X888550Y721250D02*
Y702000D01*
G01X896000Y686000D02*
Y724500D01*
G01X881200Y721300D02*
Y713500D01*
G01X884700Y708000D02*
Y721100D01*
G01X888400Y721400D02*
X888550Y721250D01*
G01X895800Y738400D02*
X894600Y737200D01*
G01X910900Y733500D02*
X905900Y728500D01*
G01X896000Y724500D02*
X894500Y726000D01*
G01X875012Y751379D02*
Y746988D01*
G01D02*
X877000Y745000D01*
G01D02*
X879704Y742296D01*
G01D02*
X879815D01*
G01X909400Y734600D02*
X906300Y731500D01*
G01D02*
X887500D01*
G01X882203Y762245D02*
X887220D01*
G01D02*
X889038Y760427D01*
G01D02*
Y757659D01*
G01D02*
X891056Y755641D01*
G01X878600Y783620D02*
X876940Y781960D01*
G01D02*
Y778750D01*
G01X892940Y784919D02*
Y778750D01*
G01X900050Y765400D02*
X905500Y770850D01*
G01D02*
Y801000D01*
G01X896550Y765400D02*
X898060Y766910D01*
G01D02*
Y772250D01*
G01X898566Y761430D02*
X896550Y763446D01*
G01D02*
Y765400D01*
G01X882203Y765745D02*
X884043D01*
G01D02*
X884788Y765000D01*
G01D02*
X886500D01*
G01X882060Y772250D02*
X884250D01*
G01D02*
X885887Y770613D01*
G01D02*
Y766811D01*
G01D02*
X886500Y766198D01*
G01D02*
Y765000D01*
G01X885306Y752148D02*
Y753071D01*
G01D02*
X882725Y755652D01*
G01D02*
Y758225D01*
G01D02*
X882229Y758721D01*
G01D02*
Y758835D01*
G01D02*
X882227D01*
G01X873700Y752691D02*
X875012Y751379D01*
G01X882590Y783990D02*
X879500Y780900D01*
G01D02*
Y778750D01*
G01X889306Y752148D02*
X886800Y754654D01*
G01D02*
Y759500D01*
G01X884778Y756198D02*
Y757478D01*
G01D02*
X886800Y759500D01*
G01X877200Y752050D02*
X877206Y752056D01*
G01D02*
Y754311D01*
G01D02*
X876036Y755481D01*
G01D02*
X877441Y756886D01*
G01D02*
Y759913D01*
G01D02*
X878578Y761050D01*
G01X881306Y752148D02*
Y755055D01*
G01D02*
X881300Y755061D01*
G01D02*
Y755871D01*
G01D02*
X880148Y757023D01*
G01D02*
Y759480D01*
G01D02*
X878578Y761050D01*
G01X875948Y755569D02*
X876036Y755481D01*
G01X894465Y755501D02*
X890463Y759503D01*
G01D02*
Y761018D01*
G01D02*
X889500Y761981D01*
G01D02*
Y765214D01*
G01D02*
X887712Y767002D01*
G01D02*
Y768693D01*
G01D02*
X887312Y769093D01*
G01D02*
Y775458D01*
G01D02*
X885312Y777458D01*
G01D02*
Y789558D01*
G01X893406Y752148D02*
Y752709D01*
G01D02*
X894465Y753768D01*
G01D02*
Y755501D01*
G01X893406Y752148D02*
X898948D01*
G01D02*
X899800Y753000D01*
G01X895500Y778750D02*
Y781500D01*
G01D02*
X896500Y782500D01*
G01D02*
X898500D01*
G01D02*
X900000Y784000D01*
G01X878600Y785250D02*
Y783620D01*
G01X874800Y786800D02*
X876350Y785250D01*
G01D02*
X878600D01*
G01X892178Y785681D02*
X892940Y784919D01*
G01X892178Y785681D02*
X888859Y789000D01*
G01D02*
X888000D01*
G01X887500Y784750D02*
Y788500D01*
G01D02*
X888000Y789000D01*
G01X905500Y801000D02*
X902600Y803900D01*
G01D02*
Y816300D01*
G01D02*
X895900Y823000D01*
G01X898406Y797648D02*
Y794494D01*
G01D02*
X898700Y794200D01*
G01X877930Y796880D02*
X875182D01*
G01D02*
X875181Y796879D01*
G01D02*
X874509D01*
G01D02*
X874033Y797355D01*
G01D02*
Y797475D01*
G01X877949Y800210D02*
X875529D01*
G01D02*
X874033Y798714D01*
G01D02*
Y797475D01*
G01X892178Y789181D02*
X892128D01*
G01D02*
X888859Y792450D01*
G01D02*
X885610D01*
G01D02*
X883200Y794860D01*
G01D02*
X874100D01*
G01X881100Y814500D02*
X883180Y812420D01*
G01D02*
X895120D01*
G01D02*
X898700Y816000D01*
G01X886288Y794372D02*
X886090Y794570D01*
G01D02*
Y800072D01*
G01D02*
X886276Y800258D01*
G01X896178Y789181D02*
X894390Y790969D01*
G01D02*
X893453D01*
G01D02*
X890500Y793922D01*
G01D02*
Y796638D01*
G01D02*
Y799783D01*
G01D02*
X890025Y800258D01*
G01D02*
X886276D01*
G01X882590Y787130D02*
Y783990D01*
G01X878460Y792910D02*
X882590Y788780D01*
G01D02*
Y787130D01*
G01X878600Y788750D02*
X876712D01*
G01D02*
X874242Y791220D01*
G01X894406Y797648D02*
Y794706D01*
G01D02*
X894200Y794500D01*
G01X882290Y796770D02*
X882049Y797011D01*
G01D02*
Y800210D01*
G01X885312Y789558D02*
X881960Y792910D01*
G01X896178Y785681D02*
X896497Y786000D01*
G01D02*
X900000D01*
G01Y784000D02*
Y786000D01*
G01X898391Y827225D02*
X910900Y814716D01*
G01X895900Y823000D02*
X888438D01*
G01D02*
X888100Y823338D01*
G01X894406Y818000D02*
X893768Y817362D01*
G01D02*
X888680D01*
G01D02*
X887362Y818680D01*
G01X890200Y819200D02*
X888900Y820500D01*
G01X897800Y825800D02*
X909400Y814200D01*
G01X908262Y23901D02*
X959399D01*
G01X918284Y25869D02*
X958768D01*
G01X909797Y48086D02*
Y36372D01*
G01D02*
X918601Y27568D01*
G01D02*
X950333D01*
G01X919262Y67762D02*
X922100Y70600D01*
G01D02*
X939900D01*
G01D02*
X946776Y63724D01*
G01X947366Y65150D02*
X940491Y72025D01*
G01D02*
X921509D01*
G01D02*
X918709Y69225D01*
G01X910945Y49234D02*
Y53889D01*
G01D02*
X909797Y55037D01*
G01X910945Y49234D02*
X909797Y48086D01*
G01X920000Y82250D02*
Y84250D01*
G01D02*
X919050Y85200D01*
G01D02*
Y85500D01*
G01X920000Y89750D02*
Y86950D01*
G01D02*
X919050Y86000D01*
G01D02*
Y85500D01*
G01X929000Y93250D02*
Y94185D01*
G01D02*
X938890Y104075D01*
G01D02*
Y106019D01*
G01D02*
X939384Y106513D01*
G01X943490Y110619D02*
X939384Y106513D01*
G01X911000Y82250D02*
Y84200D01*
G01D02*
X910000Y85200D01*
G01D02*
Y85300D01*
G01X911000Y89750D02*
X909900Y88650D01*
G01D02*
Y85400D01*
G01D02*
X910000Y85300D01*
G01X938000Y93250D02*
X939405D01*
G01D02*
X941593Y95438D01*
G01X929000Y82250D02*
X929388Y82638D01*
G01D02*
Y86112D01*
G01D02*
X929213Y86287D01*
G01D02*
Y86593D01*
G01X929000Y89750D02*
X929388Y89362D01*
G01D02*
Y86888D01*
G01D02*
X929213Y86713D01*
G01D02*
Y86593D01*
G01X938600Y99500D02*
X941962Y102862D01*
G01X929800Y105900D02*
X914650D01*
G01D02*
X908676Y99926D01*
G01X933500Y93250D02*
X934807D01*
G01D02*
X936595Y95038D01*
G01D02*
X937161D01*
G01D02*
X942857Y100734D01*
G01X915500Y93250D02*
X916807D01*
G01D02*
X923828Y100271D01*
G01D02*
X928005D01*
G01D02*
X929859Y102125D01*
G01D02*
X931101D01*
G01D02*
X934300Y105324D01*
G01D02*
Y108875D01*
G01X933500Y82250D02*
X934438Y83188D01*
G01D02*
Y86700D01*
G01X933500Y89750D02*
X934438Y88812D01*
G01D02*
Y86700D01*
G01X933069Y108500D02*
Y105331D01*
G01D02*
X930738Y103000D01*
G01D02*
X929496D01*
G01D02*
X928946Y102450D01*
G01D02*
X920200D01*
G01D02*
X915315Y97565D01*
G01D02*
X911000Y93250D01*
G01X938000Y82250D02*
X937642Y82608D01*
G01D02*
Y85562D01*
G01X938000Y89750D02*
X937642Y89392D01*
G01D02*
Y85562D01*
G01X924500Y93250D02*
X926312Y95062D01*
G01D02*
X927861D01*
G01D02*
X936555Y103756D01*
G01D02*
Y109726D01*
G01X915500Y82250D02*
Y82259D01*
G01D02*
X913979Y83780D01*
G01D02*
Y86580D01*
G01X915500Y89750D02*
Y88101D01*
G01D02*
X913979Y86580D01*
G01X920000Y93250D02*
Y93952D01*
G01D02*
X924893Y98845D01*
G01D02*
X929059D01*
G01D02*
X935400Y105186D01*
G01D02*
Y111100D01*
G01X927178Y112322D02*
X931950Y107550D01*
G01D02*
Y105450D01*
G01D02*
X930375Y103875D01*
G01D02*
X917125D01*
G01D02*
X915926Y102676D01*
G01X924500Y82250D02*
X926093Y83843D01*
G01D02*
Y85239D01*
G01X924500Y89750D02*
X926106Y88144D01*
G01D02*
Y85252D01*
G01D02*
X926093Y85239D01*
G01X920066Y116388D02*
Y114481D01*
G01X934300Y108875D02*
X932375Y110800D01*
G01D02*
Y116722D01*
G01D02*
X935053Y119400D01*
G01D02*
Y124053D01*
G01D02*
X936604Y125604D01*
G01D02*
X938000D01*
G01X918981Y117319D02*
X917700Y116038D01*
G01D02*
Y114131D01*
G01X929000Y121667D02*
X930333D01*
G01D02*
X931500Y120500D01*
G01D02*
Y110069D01*
G01D02*
X933069Y108500D01*
G01X915731Y141750D02*
X917717Y139764D01*
G01X941229Y114400D02*
X940051Y113222D01*
G01X936555Y109726D02*
X940051Y113222D01*
G01X939789Y121900D02*
Y120775D01*
G01D02*
X939751Y120737D01*
G01D02*
Y120182D01*
G01D02*
X938060Y118491D01*
G01D02*
X936691D01*
G01D02*
X934700Y116500D01*
G01D02*
Y114200D01*
G01X935400Y111100D02*
X934700Y111800D01*
G01D02*
Y114200D01*
G01X927178Y119000D02*
Y112322D01*
G01X920800Y143400D02*
Y140618D01*
G01D02*
X921654Y139764D01*
G01X911820Y157500D02*
X911792D01*
G01D02*
X909843Y159449D01*
G01X923620Y161450D02*
Y157483D01*
G01D02*
X925591Y155512D01*
G01X927559Y153543D02*
X923622D01*
G01D02*
X921654Y151575D01*
G01X909843Y143701D02*
X911817Y145675D01*
G01D02*
Y149617D01*
G01X911800Y141750D02*
X915731D01*
G01X919700Y157500D02*
Y157466D01*
G01D02*
X921654Y155512D01*
G01X915750Y153500D02*
X915792D01*
G01D02*
X917717Y151575D01*
G01X910900Y814716D02*
Y733500D01*
G01X909400Y814200D02*
Y734600D01*
G01X959399Y23901D02*
X962543Y27045D01*
G01D02*
Y28245D01*
G01D02*
X968986Y34688D01*
G01D02*
X988461D01*
G01X958768Y25869D02*
X959877Y26978D01*
G01X950333Y27568D02*
X958878Y36113D01*
G01D02*
X987870D01*
G01X947000Y71500D02*
Y73548D01*
G01D02*
X948416Y74964D01*
G01X956250Y72000D02*
Y74950D01*
G01X959300Y72000D02*
X959793Y72493D01*
G01D02*
Y75788D01*
G01X959300Y68600D02*
X960244Y67656D01*
G01D02*
Y64888D01*
G01X956250Y67900D02*
Y65750D01*
G01D02*
X957600Y64400D01*
G01D02*
X959756D01*
G01D02*
X960244Y64888D01*
G01X946776Y63724D02*
X952623D01*
G01D02*
X959147Y57200D01*
G01D02*
X983282D01*
G01X984559Y58625D02*
X959738D01*
G01D02*
X958017Y60346D01*
G01D02*
Y61799D01*
G01D02*
X954666Y65150D01*
G01D02*
X947366D01*
G01X953375Y113625D02*
Y107875D01*
G01D02*
X956000Y105250D01*
G01D02*
Y100500D01*
G01D02*
X960000Y96500D01*
G01D02*
Y95000D01*
G01X956000Y93250D02*
X958250D01*
G01D02*
X960000Y95000D01*
G01X953000Y104500D02*
Y106234D01*
G01D02*
X952500Y106734D01*
G01D02*
Y113262D01*
G01X948416Y74964D02*
X949102D01*
G01X956250Y74950D02*
X957088Y75788D01*
G01D02*
X959793D01*
G01X941593Y95438D02*
X944261D01*
G01D02*
X946438Y97615D01*
G01D02*
Y104553D01*
G01D02*
X947562Y105677D01*
G01D02*
Y113872D01*
G01X951500Y82250D02*
Y83800D01*
G01D02*
X953301Y85601D01*
G01D02*
Y85793D01*
G01X951500Y89750D02*
Y87800D01*
G01D02*
X953301Y85999D01*
G01D02*
Y85793D01*
G01X941962Y102862D02*
Y106125D01*
G01D02*
X944365Y108528D01*
G01X952900Y98900D02*
X951800Y100000D01*
G01D02*
X950042D01*
G01D02*
X947762Y102280D01*
G01D02*
Y104247D01*
G01D02*
X949893Y106378D01*
G01X942500Y82250D02*
Y85400D01*
G01D02*
X942800Y85700D01*
G01X942500Y89750D02*
Y86000D01*
G01D02*
X942800Y85700D01*
G01X942857Y100734D02*
Y105004D01*
G01D02*
X945240Y107387D01*
G01D02*
Y114083D01*
G01X960500Y100000D02*
X958362Y102138D01*
G01D02*
Y110874D01*
G01X956000Y82250D02*
Y84795D01*
G01D02*
X956687Y85482D01*
G01X956000Y89750D02*
Y86600D01*
G01D02*
X956500Y86100D01*
G01D02*
Y85669D01*
G01D02*
X956687Y85482D01*
G01X960500Y105000D02*
Y109974D01*
G01X944300Y98500D02*
Y104431D01*
G01D02*
X946478Y106609D01*
G01D02*
Y114083D01*
G01X947000Y82250D02*
Y84700D01*
G01D02*
X948200Y85900D01*
G01X947000Y89750D02*
Y87100D01*
G01D02*
X948200Y85900D01*
G01X959055Y137795D02*
X961023Y135827D01*
G01X953149Y127953D02*
Y126262D01*
G01D02*
X951561Y124674D01*
G01D02*
Y115439D01*
G01D02*
X953375Y113625D01*
G01X946749Y142631D02*
X944527Y140409D01*
G01D02*
Y129017D01*
G01D02*
X943802Y128292D01*
G01D02*
Y125915D01*
G01D02*
X944953Y124764D01*
G01D02*
Y120154D01*
G01D02*
X943802Y119003D01*
G01D02*
Y115121D01*
G01D02*
X943490Y114809D01*
G01D02*
Y110619D01*
G01X952500Y113262D02*
X950686Y115076D01*
G01D02*
Y125037D01*
G01D02*
X951561Y125912D01*
G01D02*
Y128611D01*
G01D02*
X953149Y130199D01*
G01D02*
Y131890D01*
G01X947562Y113872D02*
X949395Y115705D01*
G01D02*
Y127770D01*
G01D02*
X949212Y127953D01*
G01D02*
X949722Y128463D01*
G01D02*
Y131306D01*
G01D02*
X949987Y131571D01*
G01X974803Y133858D02*
X976771Y131890D01*
G01X944365Y108528D02*
Y114446D01*
G01D02*
X946522Y116603D01*
G01D02*
Y125112D01*
G01D02*
X945402Y126232D01*
G01D02*
Y139402D01*
G01D02*
X947400Y141400D01*
G01D02*
X951100D01*
G01D02*
X953149Y143449D01*
G01X959055Y129921D02*
Y129922D01*
G01D02*
X961023Y131890D01*
G01X966929Y133858D02*
X968897Y131890D01*
G01X949212Y139764D02*
Y137402D01*
G01D02*
X948058Y136248D01*
G01X945240Y114083D02*
X947398Y116241D01*
G01D02*
Y125474D01*
G01D02*
X946277Y126595D01*
G01D02*
Y134467D01*
G01D02*
X948058Y136248D01*
G01X958362Y110874D02*
X954736Y114500D01*
G01X960500Y109974D02*
X956200Y114274D01*
G01X970866Y137795D02*
Y141733D01*
G01X949700Y112900D02*
Y109906D01*
G01D02*
X949828Y109778D01*
G01X941339Y127953D02*
X942927Y126365D01*
G01D02*
Y115484D01*
G01D02*
X941843Y114400D01*
G01D02*
X941229D01*
G01X946478Y114083D02*
X948273Y115878D01*
G01D02*
Y125849D01*
G01D02*
X947152Y126970D01*
G01D02*
Y131996D01*
G01D02*
X950900Y135744D01*
G01D02*
Y139100D01*
G01D02*
X951564Y139764D01*
G01D02*
X953149D01*
G01X949212Y155512D02*
X946749Y153049D01*
G01D02*
Y142631D01*
G01X955118Y149606D02*
X957086Y147638D01*
G01X953149Y143449D02*
Y143701D01*
G01X959055Y161417D02*
Y157481D01*
G01D02*
X957086Y155512D01*
G01X966929Y149606D02*
X964961Y147638D01*
G01D02*
X964960D01*
G01X951181Y153543D02*
Y153544D01*
G01D02*
X953149Y155512D01*
G01X959055Y153543D02*
X961023Y151575D01*
G01X970866Y153543D02*
Y153544D01*
G01D02*
X972834Y155512D01*
G01X962992Y157480D02*
X962991D01*
G01D02*
X961023Y155512D01*
G01X955118Y141732D02*
Y141733D01*
G01D02*
X957086Y143701D01*
G01X970866Y145669D02*
X970865D01*
G01D02*
X968897Y143701D01*
G01X941339Y155512D02*
X944421D01*
G01D02*
X945030Y156121D01*
G01X970866Y141733D02*
X972834Y143701D01*
G01X970866Y161417D02*
X974803D01*
G01D02*
X976771Y159449D01*
G01X959055Y145669D02*
X961023Y143701D01*
G01X960500Y607000D02*
X960016D01*
G01D02*
X958178Y605162D01*
G01X956900Y607000D02*
X958900Y609000D01*
G01D02*
X1269000D01*
G01X988461Y34688D02*
X993653Y39880D01*
G01D02*
X994650D01*
G01X987870Y36113D02*
X989938Y38181D01*
G01D02*
Y42746D01*
G01X983282Y57200D02*
X988548Y51934D01*
G01D02*
Y48851D01*
G01D02*
X989699Y47700D01*
G01D02*
X993345D01*
G01D02*
X994609Y48964D01*
G01D02*
Y50486D01*
G01D02*
X995686Y51563D01*
G01D02*
X1010138D01*
G01X990628Y49698D02*
X990091Y50235D01*
G01D02*
Y53093D01*
G01D02*
X984559Y58625D01*
G01X989938Y42746D02*
X990312Y43120D01*
G01D02*
X997845D01*
G01D02*
X1004292Y49567D01*
G01D02*
X1015951D01*
G01X994700Y101050D02*
Y93400D01*
G01D02*
X997400Y90700D01*
G01D02*
X1050100D01*
G01X994700Y108600D02*
Y104550D01*
G01X982677Y141732D02*
X984645Y139764D01*
G01X990551Y133858D02*
X990550D01*
G01D02*
X988582Y131890D01*
G01X982677Y133858D02*
X980708Y135827D01*
G01X991332Y114300D02*
X994700Y110932D01*
G01D02*
Y108600D01*
G01X988582Y151575D02*
X990253D01*
G01D02*
X991608Y152930D01*
G01D02*
Y153979D01*
G01X987039Y153765D02*
X988685D01*
G01D02*
X988899Y153979D01*
G01D02*
X991608D01*
G01X982632Y157480D02*
X980708Y155556D01*
G01D02*
Y155512D01*
G01X982700Y149600D02*
X980424D01*
G01D02*
X979120Y148296D01*
G01D02*
Y146050D01*
G01D02*
X976771Y143701D01*
G01X978740Y161417D02*
X980708Y159449D01*
G01X978740Y153543D02*
X980708Y151575D01*
G01X1023525Y641025D02*
X1004800Y622300D01*
G01X1024950Y640434D02*
X1005391Y620875D01*
G01X1022100Y641616D02*
X1004209Y623725D01*
G01X1027900Y639352D02*
X1006573Y618025D01*
G01X1026475Y639943D02*
X1005982Y619450D01*
G01X1056151Y-4975D02*
X1022711D01*
G01X1033554Y30216D02*
X1033665Y30105D01*
G01D02*
X1040161D01*
G01D02*
X1043666Y26600D01*
G01X1044147Y10340D02*
X1041868Y12619D01*
G01D02*
Y16102D01*
G01D02*
X1041322Y16648D01*
G01D02*
X1040632D01*
G01D02*
X1037764Y19516D01*
G01D02*
X1036615D01*
G01D02*
X1033658Y22473D01*
G01D02*
X1031991D01*
G01X1025679Y23435D02*
X1031029D01*
G01D02*
X1031991Y22473D01*
G01X1025679Y25990D02*
X1033306D01*
G01D02*
X1036989Y22307D01*
G01X1042320Y18548D02*
X1040748D01*
G01D02*
X1036989Y22307D01*
G01X1039500Y56701D02*
Y60302D01*
G01D02*
X1040241Y61043D01*
G01X1039500Y56500D02*
Y56701D01*
G01D02*
X1035416Y60785D01*
G01D02*
X1028285D01*
G01D02*
X1026125Y58625D01*
G01D02*
Y57650D01*
G01X1020596Y57597D02*
Y53643D01*
G01D02*
X1020676Y53563D01*
G01X1030000Y50150D02*
Y52047D01*
G01D02*
X1027385Y54662D01*
G01D02*
X1021775D01*
G01D02*
X1020676Y53563D01*
G01X1030000Y50150D02*
X1031495Y48655D01*
G01D02*
X1033238D01*
G01D02*
X1033517Y48934D01*
G01X1010138Y51563D02*
X1010539Y51162D01*
G01D02*
X1012061D01*
G01D02*
X1012462Y51563D01*
G01D02*
X1016587D01*
G01D02*
X1024432Y43718D01*
G01X1015951Y49567D02*
X1019701Y45817D01*
G01D02*
Y45590D01*
G01D02*
X1023599Y41692D01*
G01D02*
X1026075D01*
G01D02*
X1030247Y45864D01*
G01D02*
X1035608D01*
G01D02*
X1036854Y47110D01*
G01X1030883Y112238D02*
Y108438D01*
G01X1023525Y831075D02*
Y641025D01*
G01X1024950Y678205D02*
Y640434D01*
G01X1022100Y831666D02*
Y641616D01*
G01X1027900Y829402D02*
Y639352D01*
G01X1026475Y829993D02*
Y639943D01*
G01X1024950Y830484D02*
Y679387D01*
G01D02*
X1024951Y679386D01*
G01D02*
Y678206D01*
G01D02*
X1024950Y678205D01*
G01X1056048Y863598D02*
X1023525Y831075D01*
G01X1057473Y863007D02*
X1024950Y830484D01*
G01X1028741Y889470D02*
Y838307D01*
G01D02*
X1022100Y831666D01*
G01X1068074Y869576D02*
X1027900Y829402D01*
G01X1066649Y870167D02*
X1026475Y829993D01*
G01X1094771Y-9977D02*
X1061153D01*
G01D02*
X1056151Y-4975D01*
G01X1077550Y-250D02*
X1074900Y-2900D01*
G01D02*
X1071299D01*
G01D02*
X1069700Y-1301D01*
G01D02*
Y4550D01*
G01X1074050Y3500D02*
Y450D01*
G01D02*
X1072800Y-800D01*
G01X1074050Y3500D02*
Y7600D01*
G01X1093778Y-6938D02*
X1062254D01*
G01D02*
X1061327Y-6011D01*
G01D02*
X1061283D01*
G01D02*
X1056500Y-1228D01*
G01D02*
Y9800D01*
G01X1094180Y-8552D02*
X1061852D01*
G01D02*
X1060736Y-7436D01*
G01D02*
X1060692D01*
G01D02*
X1053742Y-486D01*
G01D02*
Y10313D01*
G01X1073250Y40000D02*
X1077868D01*
G01X1052600Y14400D02*
X1053900Y15700D01*
G01D02*
X1060058D01*
G01D02*
X1060635Y15123D01*
G01D02*
X1062157D01*
G01D02*
X1062158Y15124D01*
G01D02*
X1063924D01*
G01D02*
X1065800Y17000D01*
G01D02*
X1068750D01*
G01X1043666Y26600D02*
X1044935D01*
G01D02*
X1051450Y33115D01*
G01X1068750Y28000D02*
X1066603D01*
G01D02*
X1065657Y28946D01*
G01X1051000Y41500D02*
Y37065D01*
G01D02*
X1051450Y36615D01*
G01X1044147Y10340D02*
X1046867D01*
G01D02*
X1047072Y10545D01*
G01D02*
X1047849D01*
G01D02*
X1049161Y11857D01*
G01X1076970Y30411D02*
X1075559Y29000D01*
G01D02*
X1073250D01*
G01X1046950Y33115D02*
Y31715D01*
G01D02*
X1044050Y28815D01*
G01X1047500Y41500D02*
Y37165D01*
G01D02*
X1046950Y36615D01*
G01X1044161Y17818D02*
X1044111Y17868D01*
G01D02*
X1043000D01*
G01D02*
X1042320Y18548D01*
G01X1044161Y17818D02*
X1044211Y17868D01*
G01D02*
X1045999D01*
G01D02*
X1046488Y18357D01*
G01D02*
X1048662D01*
G01X1056500Y9800D02*
X1056200Y10100D01*
G01X1053742Y10313D02*
X1055367Y11938D01*
G01D02*
X1058962D01*
G01D02*
X1060800Y10100D01*
G01X1072167Y49782D02*
X1076886D01*
G01X1065475Y48823D02*
X1067903D01*
G01D02*
X1068862Y49782D01*
G01D02*
X1072167D01*
G01X1049470Y53749D02*
X1049969Y53250D01*
G01D02*
Y47996D01*
G01D02*
X1052052Y45913D01*
G01D02*
X1059587D01*
G01D02*
X1061177Y44323D01*
G01D02*
X1061975D01*
G01X1052744Y48446D02*
X1061598D01*
G01D02*
X1061975Y48823D01*
G01X1052744Y48446D02*
X1051482Y49708D01*
G01D02*
Y54990D01*
G01D02*
X1049772Y56700D01*
G01D02*
Y57259D01*
G01X1069889Y45154D02*
X1071735Y47000D01*
G01D02*
X1076954D01*
G01X1065475Y44323D02*
X1069058D01*
G01D02*
X1069889Y45154D01*
G01X1050100Y90700D02*
X1057000Y97600D01*
G01D02*
Y107700D01*
G01D02*
Y280450D01*
G01D02*
X1087550Y311000D01*
G01X1057087Y889470D02*
Y880398D01*
G01D02*
X1056048Y879359D01*
G01D02*
Y863598D01*
G01X1060237Y889470D02*
Y882310D01*
G01D02*
X1056923Y878996D01*
G01D02*
Y874841D01*
G01D02*
X1057473Y874291D01*
G01D02*
Y863007D01*
G01X1066536Y889470D02*
Y880402D01*
G01D02*
X1068074Y878864D01*
G01D02*
Y869576D01*
G01X1063386Y889470D02*
Y882314D01*
G01D02*
X1066649Y879051D01*
G01D02*
Y870167D01*
G01X1108559Y14375D02*
X1097884Y3700D01*
G01D02*
X1088602D01*
G01D02*
X1088503Y3601D01*
G01X1077550Y7600D02*
X1082150Y3000D01*
G01D02*
X1087902D01*
G01D02*
X1088503Y3601D01*
G01X1112918Y8170D02*
X1094771Y-9977D01*
G01X1109149Y12949D02*
X1093200Y-3000D01*
G01D02*
X1085500D01*
G01X1077550Y3500D02*
Y-250D01*
G01X1085500Y-3000D02*
X1084901D01*
G01D02*
X1082162Y-261D01*
G01D02*
Y338D01*
G01D02*
X1079000Y3500D01*
G01D02*
X1077550D01*
G01X1111736Y11020D02*
X1093778Y-6938D01*
G01X1112327Y9595D02*
X1094180Y-8552D01*
G01X1077868Y40000D02*
X1084360Y46492D01*
G01X1230391Y14375D02*
X1108559D01*
G01X1077650Y12400D02*
Y7700D01*
G01D02*
X1077550Y7600D01*
G01X1230981Y12949D02*
X1109149D01*
G01X1083500Y25500D02*
X1082457Y26543D01*
G01D02*
X1080496D01*
G01D02*
X1080017Y27022D01*
G01X1076886Y49782D02*
X1083021Y55917D01*
G01D02*
X1088287D01*
G01X1084360Y46492D02*
X1087983D01*
G01D02*
X1088005Y46514D01*
G01D02*
Y46541D01*
G01X1076954Y47000D02*
X1081295Y51341D01*
G01D02*
X1096381D01*
G01D02*
X1096496Y51226D01*
G01X1087550Y311000D02*
X1281900D01*
G01X1286339Y8170D02*
X1112918D01*
G01X1285157Y11020D02*
X1111736D01*
G01X1285748Y9595D02*
X1112327D01*
G01X1288141Y659311D02*
X1168800Y778652D01*
G01D02*
Y820453D01*
G01X1288732Y660736D02*
X1171747Y777721D01*
G01D02*
Y814500D01*
G01X1289322Y662162D02*
X1176738Y774746D01*
G01D02*
Y806500D01*
G01X1171747Y880947D02*
Y814500D01*
G01X1176738Y819061D02*
Y806500D01*
G01X1168607Y823010D02*
Y834500D01*
G01X1168800Y820453D02*
X1168607Y820646D01*
G01D02*
Y823010D01*
G01Y872438D02*
Y834500D01*
G01X1176772Y852204D02*
X1173172Y848604D01*
G01D02*
Y822627D01*
G01D02*
X1176738Y819061D01*
G01X1170473Y889470D02*
Y874304D01*
G01D02*
X1168607Y872438D01*
G01X1173623Y889470D02*
Y882823D01*
G01D02*
X1171747Y880947D01*
G01X1176772Y889470D02*
Y852204D01*
G01X1198134Y420766D02*
X1196600Y422300D01*
G01X1198134Y420766D02*
X1201000Y417900D01*
G01X1179723Y418777D02*
X1178200Y420300D01*
G01X1196600Y416200D02*
X1182300D01*
G01D02*
X1179723Y418777D01*
G01X1251225Y35209D02*
X1230391Y14375D01*
G01X1252650Y34618D02*
X1230981Y12949D01*
G01X1259398Y401632D02*
X1237305Y423725D01*
G01X1215842Y739459D02*
X1288301Y667000D01*
G01X1217267Y740633D02*
X1286800Y671100D01*
G01X1215842Y865842D02*
Y739459D01*
G01X1217267Y865251D02*
Y740633D01*
G01X1217717Y889470D02*
Y883083D01*
G01D02*
X1219455Y881345D01*
G01D02*
Y879327D01*
G01D02*
X1220924Y877858D01*
G01D02*
Y870924D01*
G01D02*
X1215842Y865842D01*
G01X1220867Y889470D02*
Y879746D01*
G01D02*
X1222349Y878264D01*
G01D02*
Y870333D01*
G01D02*
X1217267Y865251D01*
G01X1251225Y70709D02*
Y35209D01*
G01X1252650Y60250D02*
Y34618D01*
G01X1259387Y78871D02*
X1251225Y70709D01*
G01X1259387Y64292D02*
X1256692D01*
G01D02*
X1252650Y60250D01*
G01X1259387Y79252D02*
Y78871D01*
G01X1255000Y317300D02*
Y323000D01*
G01D02*
Y339600D01*
G01D02*
X1259398Y343998D01*
G01D02*
Y401632D01*
G01X1272000Y349500D02*
Y341500D01*
G01D02*
X1274030Y339470D01*
G01X1279163Y334337D02*
X1274030Y339470D01*
G01X1275060Y345690D02*
Y343940D01*
G01D02*
X1280836Y338164D01*
G01X1264820Y402100D02*
Y356000D01*
G01D02*
Y349320D01*
G01X1272500Y350000D02*
X1272000Y349500D01*
G01X1277620D02*
Y346380D01*
G01D02*
X1286000Y338000D01*
G01X1273500Y406500D02*
Y400500D01*
G01X1258085Y425325D02*
X1273500Y409910D01*
G01D02*
Y406500D01*
G01X1258000Y421500D02*
Y408920D01*
G01D02*
X1264820Y402100D01*
G01X1270428Y426750D02*
X1312839Y384339D01*
G01X1275462Y599462D02*
X1314422Y638422D01*
G01X1300000Y637000D02*
X1272000Y609000D01*
G01D02*
X1269000D01*
G01X1269336Y603737D02*
X1318845Y653246D01*
G01X1321695Y650195D02*
X1272387Y600887D01*
G01X1269927Y602312D02*
X1320270Y652655D01*
G01X1301520Y94499D02*
Y23351D01*
G01D02*
X1286339Y8170D01*
G01X1298670Y95681D02*
Y24533D01*
G01D02*
X1285157Y11020D01*
G01X1300095Y95090D02*
Y23942D01*
G01D02*
X1285748Y9595D01*
G01X1305124Y119145D02*
Y98103D01*
G01D02*
X1301520Y94499D01*
G01X1302274Y120327D02*
Y99285D01*
G01D02*
X1298670Y95681D01*
G01X1303699Y119736D02*
Y98694D01*
G01D02*
X1300095Y95090D01*
G01X1306522Y151371D02*
Y120543D01*
G01D02*
X1305124Y119145D01*
G01X1303650Y154679D02*
Y121703D01*
G01D02*
X1302274Y120327D01*
G01X1305075Y153603D02*
Y121112D01*
G01D02*
X1303699Y119736D01*
G01X1315130Y159979D02*
X1306522Y151371D01*
G01X1318255Y169284D02*
X1303650Y154679D01*
G01X1319250Y167778D02*
X1305075Y153603D01*
G01X1284505Y308395D02*
X1288900Y304000D01*
G01X1281900Y311000D02*
X1284505Y308395D01*
G01X1323200Y349003D02*
X1308534Y334337D01*
G01D02*
X1279163D01*
G01X1286000Y338000D02*
X1295000D01*
G01D02*
X1308165D01*
G01D02*
X1319352Y349187D01*
G01X1282170Y346580D02*
X1288250Y340500D01*
G01D02*
X1307500D01*
G01D02*
X1317927Y350927D01*
G01X1280836Y338164D02*
X1283238Y335762D01*
G01D02*
X1307943D01*
G01D02*
X1321775Y349594D01*
G01X1290125Y382875D02*
X1296500Y376500D01*
G01D02*
X1298500D01*
G01X1316502Y382821D02*
X1310181Y376500D01*
G01D02*
X1298500D01*
G01X1281900Y346580D02*
X1282170D01*
G01X1319352Y393447D02*
X1280349Y432450D01*
G01X1297625Y382375D02*
X1297750Y382500D01*
G01D02*
X1311000D01*
G01D02*
X1312839Y384339D01*
G01X1279167Y429600D02*
X1316502Y392265D01*
G01X1317927Y392856D02*
X1279758Y431025D01*
G01X1296500Y386500D02*
X1295000Y385000D01*
G01D02*
Y381500D01*
G01D02*
X1297000Y379500D01*
G01D02*
X1305500D01*
G01D02*
X1311165D01*
G01D02*
X1315077Y383412D01*
G01Y391674D02*
X1278576Y428175D01*
G01X1309288Y437276D02*
X1323200Y423364D01*
G01X1321775Y422773D02*
X1308697Y435851D01*
G01X1324545Y642045D02*
X1305432Y622932D01*
G01X1301000Y618500D02*
X1305432Y622932D01*
G01X1312319Y659312D02*
X1290504D01*
G01D02*
X1290503Y659311D01*
G01D02*
X1288141D01*
G01X1302128Y680617D02*
X1301400D01*
G01D02*
X1298017Y684000D01*
G01X1288301Y667000D02*
X1292000D01*
G01X1297500Y664000D02*
X1294500Y667000D01*
G01D02*
X1292000D01*
G01X1312954Y664000D02*
X1309691Y660737D01*
G01D02*
X1289913D01*
G01D02*
X1289912Y660736D01*
G01D02*
X1288732D01*
G01X1310207Y664000D02*
X1308369Y662162D01*
G01D02*
X1289322D01*
G01X1306128Y680617D02*
X1304000Y682745D01*
G01X1294354Y707104D02*
Y675765D01*
G01D02*
X1299382Y670737D01*
G01D02*
X1318917D01*
G01X1310128Y680617D02*
Y682628D01*
G01X1317768Y665838D02*
X1298233D01*
G01D02*
X1289590Y674481D01*
G01D02*
Y730561D01*
G01X1295779Y689279D02*
Y676356D01*
G01D02*
X1299973Y672162D01*
G01D02*
X1319508D01*
G01X1292929Y713929D02*
Y675174D01*
G01D02*
X1299415Y668688D01*
G01D02*
X1318950D01*
G01X1318359Y667263D02*
X1298824D01*
G01D02*
X1291504Y674583D01*
G01D02*
Y718004D01*
G01X1310222Y706719D02*
Y709500D01*
G01D02*
X1310722Y710000D01*
G01D02*
X1313000D01*
G01X1310900Y713650D02*
X1311250Y714000D01*
G01D02*
X1315000D01*
G01X1302128Y685500D02*
X1299517D01*
G01D02*
X1298017Y684000D01*
G01X1302000Y706750D02*
X1307631D01*
G01D02*
X1307662Y706719D01*
G01X1298000Y703500D02*
X1298750D01*
G01D02*
X1302000Y706750D01*
G01X1298000Y707250D02*
Y703500D01*
G01X1307000Y686500D02*
X1304544Y688956D01*
G01D02*
X1303709D01*
G01X1304000Y682745D02*
Y686245D01*
G01D02*
X1303440Y686805D01*
G01D02*
Y688687D01*
G01D02*
X1303709Y688956D01*
G01X1298000Y710750D02*
X1294354Y707104D01*
G01X1310128Y682628D02*
X1311793Y684293D01*
G01D02*
X1312132D01*
G01X1302000Y695500D02*
X1295779Y689279D01*
G01X1295714Y716714D02*
X1292929Y713929D01*
G01X1310900Y717150D02*
X1316350D01*
G01X1310500Y723000D02*
X1306500D01*
G01D02*
X1305650Y723850D01*
G01D02*
Y725500D01*
G01X1310100Y726150D02*
X1306300D01*
G01D02*
X1305650Y725500D01*
G01X1312790Y734838D02*
X1298500D01*
G01X1289590Y730561D02*
X1293867Y734838D01*
G01D02*
X1298500D01*
G01X1316000Y719737D02*
X1309148D01*
G01D02*
X1308911Y719500D01*
G01D02*
X1298500D01*
G01D02*
X1295714Y716714D01*
G01X1291504Y718004D02*
X1294662Y721162D01*
G01D02*
X1319226D01*
G01X1323195Y161642D02*
X1321532Y159979D01*
G01D02*
X1315130D01*
G01X1323195Y161642D02*
X1348785D01*
G01X1368540Y169284D02*
X1318255D01*
G01X1351991Y167778D02*
X1319250D01*
G01X1323200Y423364D02*
Y349003D01*
G01X1319352Y349187D02*
Y393447D01*
G01X1317927Y350927D02*
Y392856D01*
G01X1321775Y349594D02*
Y422773D01*
G01X1316502Y392265D02*
Y382821D01*
G01X1315077Y383412D02*
Y391674D01*
G01X1364000Y394595D02*
X1316406Y442189D01*
G01X1387925Y374702D02*
X1317588Y445039D01*
G01X1316997Y443614D02*
X1384842Y375769D01*
G01X1323120Y666534D02*
Y647120D01*
G01D02*
X1314422Y638422D01*
G01X1324545Y667125D02*
Y642045D01*
G01X1331000Y658200D02*
Y662000D01*
G01X1317007Y664000D02*
X1312319Y659312D01*
G01X1322128Y680617D02*
Y683598D01*
G01X1330128Y680617D02*
X1331617D01*
G01D02*
X1333052Y682052D01*
G01X1327200Y661800D02*
X1327700Y662300D01*
G01D02*
Y664300D01*
G01D02*
X1332400Y669000D01*
G01D02*
X1339500D01*
G01D02*
X1344200Y673700D01*
G01D02*
X1345541D01*
G01D02*
X1347788Y675947D01*
G01X1343005Y683495D02*
Y681005D01*
G01D02*
X1343000Y681000D01*
G01X1338128Y680617D02*
X1342617D01*
G01D02*
X1343000Y681000D01*
G01X1318117Y682451D02*
Y680886D01*
G01X1314128Y680617D02*
X1317848D01*
G01D02*
X1318117Y680886D01*
G01X1313607Y664000D02*
X1312954D01*
G01X1340000Y674000D02*
X1338162Y672162D01*
G01D02*
X1330000D01*
G01X1326128Y674000D02*
X1327966Y672162D01*
G01D02*
X1330000D01*
G01X1318917Y670737D02*
X1323120Y666534D01*
G01X1326128Y680617D02*
Y684990D01*
G01X1318845Y653246D02*
Y664761D01*
G01D02*
X1317768Y665838D01*
G01X1319508Y672162D02*
X1324545Y667125D01*
G01X1318950Y668688D02*
X1321695Y665943D01*
G01D02*
Y650195D01*
G01X1320270Y652655D02*
Y665352D01*
G01D02*
X1318359Y667263D01*
G01X1313000Y710000D02*
X1315000Y712000D01*
G01D02*
Y714000D01*
G01X1330400Y690150D02*
X1333350D01*
G01D02*
X1334937Y688563D01*
G01D02*
Y687447D01*
G01D02*
X1336795Y685589D01*
G01D02*
Y685141D01*
G01X1322128Y683598D02*
X1321928Y683798D01*
G01X1317384Y716116D02*
Y708739D01*
G01D02*
X1317000Y708355D01*
G01D02*
Y700111D01*
G01D02*
X1320251Y696860D01*
G01D02*
Y690751D01*
G01D02*
X1319500Y690000D01*
G01X1321928Y683798D02*
X1320251Y685475D01*
G01D02*
Y689249D01*
G01D02*
X1319500Y690000D01*
G01X1312900Y690150D02*
X1313949D01*
G01D02*
X1316838Y687261D01*
G01D02*
Y686329D01*
G01D02*
X1318500Y684667D01*
G01X1329500D02*
X1330833Y686000D01*
G01D02*
X1333000D01*
G01D02*
X1333020Y686020D01*
G01D02*
X1333052D01*
G01Y682052D02*
Y686020D01*
G01X1325900Y714150D02*
X1325162Y713412D01*
G01D02*
Y707219D01*
G01X1319500Y709250D02*
Y710700D01*
G01D02*
X1322300Y713500D01*
G01X1325900Y714150D02*
X1322950D01*
G01D02*
X1322300Y713500D01*
G01X1337000Y716168D02*
X1335093Y714261D01*
G01D02*
Y711435D01*
G01D02*
X1335338Y711190D01*
G01D02*
Y708500D01*
G01D02*
X1332562Y705724D01*
G01D02*
Y699392D01*
G01D02*
X1336760Y695194D01*
G01D02*
Y690959D01*
G01D02*
X1336362Y690561D01*
G01D02*
Y689039D01*
G01D02*
X1337439Y687962D01*
G01D02*
X1337538D01*
G01D02*
X1339212Y686288D01*
G01D02*
Y685993D01*
G01D02*
X1339934Y685271D01*
G01D02*
Y683832D01*
G01D02*
X1342668D01*
G01D02*
X1343005Y683495D01*
G01X1315000Y686500D02*
X1315413Y686087D01*
G01D02*
Y685155D01*
G01D02*
X1318117Y682451D01*
G01X1312782Y700219D02*
X1314876D01*
G01D02*
X1317500Y697595D01*
G01D02*
Y695000D01*
G01X1312900Y693650D02*
X1316150D01*
G01D02*
X1317500Y695000D01*
G01X1340900Y714150D02*
X1338779D01*
G01D02*
X1337338Y712709D01*
G01X1341662Y707219D02*
Y713388D01*
G01D02*
X1340900Y714150D01*
G01X1336000Y705250D02*
Y707146D01*
G01D02*
X1336763Y707909D01*
G01D02*
Y712134D01*
G01D02*
X1337338Y712709D01*
G01X1329900Y714150D02*
X1331824Y716074D01*
G01X1327722Y707219D02*
Y709722D01*
G01D02*
X1329000Y711000D01*
G01D02*
X1332159D01*
G01D02*
X1333659Y712500D01*
G01D02*
Y716054D01*
G01X1330282Y700719D02*
Y697718D01*
G01D02*
X1331000Y697000D01*
G01D02*
X1332938D01*
G01D02*
X1334195Y695743D01*
G01D02*
Y694005D01*
G01X1330400Y693650D02*
X1333840D01*
G01D02*
X1334195Y694005D01*
G01X1344900Y714150D02*
X1345588Y714838D01*
G01D02*
X1350162D01*
G01X1344222Y707219D02*
Y704778D01*
G01D02*
X1344919Y704081D01*
G01D02*
X1350567D01*
G01X1326128Y684990D02*
X1326758Y685620D01*
G01D02*
Y686678D01*
G01X1334128Y732667D02*
X1332975Y733820D01*
G01D02*
Y739975D01*
G01D02*
X1352500Y759500D01*
G01X1315000Y723000D02*
X1317500D01*
G01D02*
X1318228Y723728D01*
G01D02*
Y725500D01*
G01X1314628Y726117D02*
X1317611D01*
G01D02*
X1318228Y725500D01*
G01X1338128Y738000D02*
Y732872D01*
G01X1340500Y742500D02*
X1338128Y740128D01*
G01D02*
Y738000D01*
G01X1316350Y717150D02*
X1317384Y716116D01*
G01X1342000Y732500D02*
X1355000Y719500D01*
G01X1329900Y717650D02*
X1331000D01*
G01D02*
X1331662Y718312D01*
G01D02*
X1336000D01*
G01D02*
X1337000Y717312D01*
G01D02*
Y716168D01*
G01X1330128Y732667D02*
X1331550Y734089D01*
G01D02*
Y740566D01*
G01D02*
X1341492Y750508D01*
G01X1333500Y723000D02*
X1331000D01*
G01D02*
X1330000Y724000D01*
G01D02*
Y724500D01*
G01X1334128Y726117D02*
X1331617D01*
G01D02*
X1330000Y724500D01*
G01X1338128Y726117D02*
X1338511Y726500D01*
G01D02*
X1342000D01*
G01X1337500Y723000D02*
X1338083D01*
G01D02*
X1338508Y723425D01*
G01D02*
X1340925D01*
G01D02*
X1342000Y724500D01*
G01D02*
Y726500D01*
G01X1325500Y726250D02*
Y723087D01*
G01D02*
X1325600Y722987D01*
G01D02*
X1327425Y721162D01*
G01D02*
X1338261D01*
G01D02*
X1339099Y722000D01*
G01D02*
X1344070D01*
G01D02*
X1344237Y721833D01*
G01X1344900Y717650D02*
Y721170D01*
G01D02*
X1344237Y721833D01*
G01X1331824Y716074D02*
X1333639D01*
G01X1333659Y716054D02*
X1333639Y716074D01*
G01X1314628Y733000D02*
X1312790Y734838D01*
G01X1325900Y717650D02*
X1318087D01*
G01D02*
X1316000Y719737D01*
G01X1340900Y717650D02*
X1338813Y719737D01*
G01D02*
X1326000D01*
G01D02*
X1325974Y719763D01*
G01D02*
X1320625D01*
G01D02*
X1320500Y719888D01*
G01X1319226Y721162D02*
X1320500Y719888D01*
G01X1331123Y795877D02*
X1356100Y770900D01*
G01X1329698Y795202D02*
X1354675Y770225D01*
G01Y763691D02*
X1341492Y750508D01*
G01D02*
X1340500Y751500D01*
G01X1346877Y816277D02*
X1333800D01*
G01D02*
X1331123Y813600D01*
G01D02*
Y795877D01*
G01X1329500Y817200D02*
Y814962D01*
G01D02*
X1329698Y814764D01*
G01D02*
Y795202D01*
G01X1329700Y817400D02*
X1329500Y817200D01*
G01X1346102Y817702D02*
X1331602D01*
G01D02*
X1331300Y817400D01*
G01D02*
X1329700D01*
G01X1378289Y169235D02*
X1374174Y173350D01*
G01D02*
Y175745D01*
G01X1378289Y169235D02*
X1378581Y168943D01*
G01D02*
X1383164D01*
G01X1374789Y169235D02*
X1374740Y169284D01*
G01D02*
X1368540D01*
G01X1382179Y163528D02*
X1379473D01*
G01D02*
X1369151D01*
G01D02*
X1367770Y164909D01*
G01D02*
X1354860D01*
G01D02*
X1351991Y167778D01*
G01X1365804Y185197D02*
Y189733D01*
G01Y185197D02*
X1365933Y185326D01*
G01D02*
X1369649D01*
G01D02*
X1371614Y183361D01*
G01D02*
Y182245D01*
G01X1380669Y175745D02*
X1376734D01*
G01X1364000Y299500D02*
Y280500D01*
G01Y299500D02*
Y394595D01*
G01X1351500Y671200D02*
Y675000D01*
G01X1347788Y675947D02*
Y677288D01*
G01D02*
X1347900Y677400D01*
G01D02*
Y689150D01*
G01X1346900Y693650D02*
X1350150D01*
G01D02*
X1352000Y695500D01*
G01D02*
Y698000D01*
G01X1346782Y700719D02*
X1351281D01*
G01D02*
X1352000Y700000D01*
G01D02*
Y698000D01*
G01X1346900Y690150D02*
X1351650D01*
G01D02*
X1355000Y693500D01*
G01D02*
Y716000D01*
G01X1347900Y689150D02*
X1346900Y690150D01*
G01X1350162Y714838D02*
X1352000Y713000D01*
G01D02*
Y708500D01*
G01X1350567Y704081D02*
X1352000Y705514D01*
G01D02*
Y708500D01*
G01X1355000Y719500D02*
Y716000D01*
G01X1353500Y758500D02*
X1352500Y759500D01*
G01X1356100Y770900D02*
Y763100D01*
G01D02*
X1352500Y759500D01*
G01X1354675Y770225D02*
Y763691D01*
G01X1358015Y827415D02*
X1346877Y816277D01*
G01X1349500Y879700D02*
Y846500D01*
G01D02*
X1357900Y838100D01*
G01D02*
Y836001D01*
G01D02*
X1358015Y835886D01*
G01D02*
Y827415D01*
G01X1348075Y874291D02*
Y845909D01*
G01D02*
X1356475Y837509D01*
G01D02*
Y835410D01*
G01D02*
X1356590Y835295D01*
G01D02*
Y828190D01*
G01D02*
X1346102Y817702D01*
G01X1353150Y889470D02*
Y883350D01*
G01D02*
X1349500Y879700D01*
G01X1350000Y889470D02*
Y881438D01*
G01D02*
X1348625Y880063D01*
G01D02*
Y874841D01*
G01D02*
X1348075Y874291D01*
G01X1387196Y174160D02*
X1389513Y176477D01*
G01X1384842Y176201D02*
Y170430D01*
G01D02*
X1385402Y169870D01*
G01D02*
Y166751D01*
G01D02*
X1382179Y163528D01*
G01X1385467Y180543D02*
X1380669Y175745D01*
G01X1389513Y176477D02*
Y186503D01*
G01D02*
X1387926Y188090D01*
G01D02*
X1387925Y374702D01*
G01X1384842Y375769D02*
Y187716D01*
G01D02*
X1388078Y184480D01*
G01D02*
Y179437D01*
G01D02*
X1384842Y176201D01*
M02*
